# Altium SchDoc records: POWER.SchDoc
|HEADER=Protel for Windows - Schematic Capture Binary File Version 5.0|Weight=1467|MinorVersion=2
|RECORD=31|FontIdCount=6|Size1=10|FontName1=Times New Roman|Size2=12|FontName2=Arial|Size3=8|FontName3=Arial|Size4=10|FontName4=Arial|Size5=14|FontName5=Arial|Size6=12|Underline6=T|FontName6=Arial|UseMBCS=T|IsBOC=T|HotSpotGridOn=T|HotSpotGridSize=4|SheetStyle=12|SystemFont=4|BorderOn=T|SheetNumberSpaceSize=12|AreaColor=16317695|SnapGridOn=T|SnapGridSize=10|VisibleGridOn=T|VisibleGridSize=10|CustomX=2338|CustomX_Frac=58268|CustomY=1653|CustomY_Frac=54331|CustomXZones=8|CustomYZones=6|CustomMarginWidth=19|CustomMarginWidth_Frac=80000|ShowTemplateGraphics=T|TemplateFileName=C:\Users\<user>\Documents\Altium\AD20\Templates\Timecard.SchDot|Display_Unit=0
|RECORD=39|IsNotAccesible=T|OwnerPartId=-1|FileName=C:\Users\<user>\Documents\Altium\AD20\Templates\Timecard.SchDot
|RECORD=4|OwnerIndex=1|OwnerPartId=-1|Location.X=1594|Location.Y=39|Color=8388608|FontID=6|Text=timingcard.com|URL=http://timingcard.com
|RECORD=6|OwnerIndex=1|IndexInSheet=1|OwnerPartId=-1|LocationCount=2|X1=1680|Y1=35|X2=1576|Y2=35
|RECORD=4|OwnerIndex=1|IndexInSheet=2|OwnerPartId=-1|Location.X=1614|Location.X_Frac=42446|Location.Y=19|Location.Y_Frac=96838|FontID=2|Text==SheetNumber
|RECORD=4|OwnerIndex=1|IndexInSheet=3|OwnerPartId=-1|Location.X=1581|Location.X_Frac=42446|Location.Y=29|Location.Y_Frac=96838|Justification=3|FontID=3|Text=SHEET
|RECORD=4|OwnerIndex=1|IndexInSheet=4|OwnerPartId=-1|Location.X=1639|Location.X_Frac=42446|Location.Y=29|Location.Y_Frac=96838|Justification=3|FontID=3|Text=OF
|RECORD=6|OwnerIndex=1|IndexInSheet=5|OwnerPartId=-1|LineWidth=1|LocationCount=2|X1=1679|X1_Frac=42446|Y1=105|Y1_Frac=96838|X2=1576|Y2=106
|RECORD=4|OwnerIndex=1|IndexInSheet=6|OwnerPartId=-1|Location.X=1658|Location.Y=20|FontID=2|Text==SheetTotal
|RECORD=30|OwnerIndex=1|IndexInSheet=7|OwnerPartId=-1|Location.X=1578|Location.Y=53|Corner.X=1673|Corner.X_Frac=88801|Corner.Y=103|KeepAspect=T|FileName=C:\Users\<user>\Desktop\Timecard Logo\TIMECARD.jpg
|RECORD=6|OwnerIndex=1|IndexInSheet=8|OwnerPartId=-1|LineWidth=1|LocationCount=2|X1=1576|X1_Frac=3162|Y1=105|Y1_Frac=42446|X2=1576|Y2=20
|RECORD=6|OwnerIndex=1|IndexInSheet=9|OwnerPartId=-1|LocationCount=2|X1=1680|Y1=51|X2=1576|Y2=51
|RECORD=41|IndexInSheet=1|OwnerPartId=-1|Color=8388608|FontID=1|IsHidden=T|Text=*|Name=CurrentTime|ReadOnlyState=1
|RECORD=41|IndexInSheet=2|OwnerPartId=-1|Color=8388608|FontID=1|IsHidden=T|Text=*|Name=CurrentDate|ReadOnlyState=1
|RECORD=41|IndexInSheet=3|OwnerPartId=-1|Color=8388608|FontID=1|IsHidden=T|Text=*|Name=Time|ReadOnlyState=1
|RECORD=41|IndexInSheet=4|OwnerPartId=-1|Color=8388608|FontID=1|IsHidden=T|Text=*|Name=Date|ReadOnlyState=1
|RECORD=41|IndexInSheet=5|OwnerPartId=-1|Color=8388608|FontID=1|IsHidden=T|Text=*|Name=DocumentFullPathAndName|ReadOnlyState=1
|RECORD=41|IndexInSheet=6|OwnerPartId=-1|Color=8388608|FontID=1|IsHidden=T|Text=*|Name=DocumentName|ReadOnlyState=1
|RECORD=41|IndexInSheet=7|OwnerPartId=-1|Color=8388608|FontID=1|IsHidden=T|Text=*|Name=ModifiedDate|ReadOnlyState=1
|RECORD=41|IndexInSheet=8|OwnerPartId=-1|Color=8388608|FontID=1|IsHidden=T|Text=*|Name=ApprovedBy|ReadOnlyState=1
|RECORD=41|IndexInSheet=9|OwnerPartId=-1|Color=8388608|FontID=1|IsHidden=T|Text=*|Name=CheckedBy|ReadOnlyState=1
|RECORD=41|IndexInSheet=10|OwnerPartId=-1|Color=8388608|FontID=1|IsHidden=T|Text=<name>|Name=Author|ReadOnlyState=1
|RECORD=41|IndexInSheet=11|OwnerPartId=-1|Color=8388608|FontID=1|IsHidden=T|Text=*|Name=CompanyName|ReadOnlyState=1
|RECORD=41|IndexInSheet=12|OwnerPartId=-1|Color=8388608|FontID=1|IsHidden=T|Text=*|Name=DrawnBy|ReadOnlyState=1
|RECORD=41|IndexInSheet=13|OwnerPartId=-1|Color=8388608|FontID=1|IsHidden=T|Text=*|Name=Engineer|ReadOnlyState=1
|RECORD=41|IndexInSheet=14|OwnerPartId=-1|Color=8388608|FontID=1|IsHidden=T|Text=*|Name=Organization|ReadOnlyState=1
|RECORD=41|IndexInSheet=15|OwnerPartId=-1|Color=8388608|FontID=1|IsHidden=T|Text=*|Name=Address1|ReadOnlyState=1
|RECORD=41|IndexInSheet=16|OwnerPartId=-1|Color=8388608|FontID=1|IsHidden=T|Text=*|Name=Address2|ReadOnlyState=1
|RECORD=41|IndexInSheet=17|OwnerPartId=-1|Color=8388608|FontID=1|IsHidden=T|Text=*|Name=Address3|ReadOnlyState=1
|RECORD=41|IndexInSheet=18|OwnerPartId=-1|Color=8388608|FontID=1|IsHidden=T|Text=*|Name=Address4|ReadOnlyState=1
|RECORD=41|IndexInSheet=19|OwnerPartId=-1|Color=8388608|FontID=1|IsHidden=T|Text=Grandmaster Power Supplies|Name=Title|ReadOnlyState=1
|RECORD=41|IndexInSheet=20|OwnerPartId=-1|Color=8388608|FontID=1|IsHidden=T|Text=*|Name=DocumentNumber|ReadOnlyState=1
|RECORD=41|IndexInSheet=21|OwnerPartId=-1|Color=8388608|FontID=1|IsHidden=T|Text=A|Name=Revision|ReadOnlyState=1
|RECORD=41|IndexInSheet=22|OwnerPartId=-1|Color=8388608|FontID=1|IsHidden=T|Text=2|Name=SheetNumber|ReadOnlyState=1
|RECORD=41|IndexInSheet=23|OwnerPartId=-1|Color=8388608|FontID=1|IsHidden=T|Text=7|Name=SheetTotal|ReadOnlyState=1
|RECORD=41|IndexInSheet=24|OwnerPartId=-1|Color=8388608|FontID=1|IsHidden=T|Text=*|Name=Rule|ReadOnlyState=1
|RECORD=41|IndexInSheet=25|OwnerPartId=-1|Color=8388608|FontID=1|IsHidden=T|Text=*|Name=ImagePath|ReadOnlyState=1
|RECORD=41|IndexInSheet=26|OwnerPartId=-1|Color=8388608|FontID=1|IsHidden=T|Text=*|Name=ProjectName|ReadOnlyState=1
|RECORD=41|IndexInSheet=27|OwnerPartId=-1|Color=8388608|FontID=1|IsHidden=T|Text=*|Name=Application_BuildNumber|ReadOnlyState=1
|RECORD=41|IndexInSheet=28|OwnerPartId=-1|Location.X=21474|Location.X_Frac=83647|Location.Y=21464|Location.Y_Frac=83647|Color=8388608|FontID=1|IsHidden=T|Text=01910|Name=Customer
|RECORD=41|IndexInSheet=29|OwnerPartId=-1|Location.X=1000|Location.Y=10|Color=8388608|FontID=1|IsHidden=T|Text=*|Name=DocStatus
|RECORD=17|IndexInSheet=30|OwnerPartId=-1|ShowNetName=T|Location.X=380|Location.Y=920|Orientation=1|Color=128|FontID=1|Text=+12V
|RECORD=17|IndexInSheet=31|OwnerPartId=-1|Style=4|ShowNetName=T|Location.X=380|Location.Y=810|Orientation=3|Color=128|FontID=1|Text=GND
|RECORD=17|IndexInSheet=32|OwnerPartId=-1|ShowNetName=T|Location.X=930|Location.Y=950|Orientation=1|Color=128|FontID=1|Text=+5.0V
|RECORD=17|IndexInSheet=33|OwnerPartId=-1|ShowNetName=T|Location.X=1330|Location.Y=440|Orientation=1|Color=128|FontID=1|Text=+3.3V
|RECORD=17|IndexInSheet=34|OwnerPartId=-1|Style=4|ShowNetName=T|Location.X=580|Location.Y=730|Orientation=3|Color=128|FontID=1|Text=GND
|RECORD=17|IndexInSheet=35|OwnerPartId=-1|Style=4|ShowNetName=T|Location.X=860|Location.Y=730|Orientation=3|Color=128|FontID=1|Text=GND
|RECORD=17|IndexInSheet=36|OwnerPartId=-1|Style=4|ShowNetName=T|Location.X=1330|Location.Y=280|Orientation=3|Color=128|FontID=1|Text=GND
|RECORD=17|IndexInSheet=37|OwnerPartId=-1|Style=4|ShowNetName=T|Location.X=530|Location.Y=280|Orientation=3|Color=128|FontID=1|Text=GND
|RECORD=17|IndexInSheet=38|OwnerPartId=-1|Style=4|ShowNetName=T|Location.X=810|Location.Y=280|Orientation=3|Color=128|FontID=1|Text=GND
|RECORD=17|IndexInSheet=39|OwnerPartId=-1|ShowNetName=T|Location.X=970|Location.Y=550|Orientation=1|Color=128|FontID=1|Text=+3.3V
|RECORD=17|IndexInSheet=40|OwnerPartId=-1|ShowNetName=T|Location.X=530|Location.Y=960|Orientation=1|Color=128|FontID=1|Text=+12V
|RECORD=17|IndexInSheet=41|OwnerPartId=-1|ShowNetName=T|Location.X=530|Location.Y=560|Orientation=1|Color=128|FontID=1|Text=+12V
|RECORD=1|LibReference=DFLZ39|ComponentDescription=DIO, ZENER, DFLZ39, 39V, 5%, 1W, SOD123FL|PartCount=2|DisplayModeCount=1|IndexInSheet=42|OwnerPartId=-1|Location.X=160|Location.Y=900|Orientation=3|CurrentPartId=1|LibraryPath=*|SourceLibraryName=Passives.IntLib|TargetFileName=*|AreaColor=11599871|Color=128|PartIDLocked=F|DesignItemId=DFLZ39|AllPinCount=2
|RECORD=41|OwnerIndex=53|OwnerPartId=-1|Location.X=158|Location.Y=911|Color=8388608|FontID=2|IsHidden=T|Text=DFLZ39-TP|Name=MFG PART NUM
|RECORD=41|OwnerIndex=53|IndexInSheet=1|OwnerPartId=-1|Location.X=158|Location.Y=911|Color=8388608|FontID=2|IsHidden=T|Text=9/4/2013|Name=MODIFY DATE
|RECORD=41|OwnerIndex=53|IndexInSheet=2|OwnerPartId=-1|Location.X=158|Location.Y=911|Color=8388608|FontID=2|IsHidden=T|Text=MICRO COMM|Name=MFG NAME
|RECORD=41|OwnerIndex=53|IndexInSheet=3|OwnerPartId=-1|Location.X=158|Location.Y=911|Color=8388608|FontID=2|IsHidden=T|Text=DIO, ZENER|Name=CATEGORY
|RECORD=41|OwnerIndex=53|IndexInSheet=4|OwnerPartId=-1|Location.X=158|Location.Y=911|Color=8388608|FontID=2|IsHidden=T|Name=DATE
|RECORD=41|OwnerIndex=53|IndexInSheet=5|OwnerPartId=-1|Location.X=158|Location.Y=911|Color=8388608|FontID=2|IsHidden=T|Text=150C|Name=MAXTEMP
|RECORD=41|OwnerIndex=53|IndexInSheet=6|OwnerPartId=-1|Location.X=158|Location.Y=911|Color=8388608|FontID=2|IsHidden=T|Text=-55C|Name=MINTEMP
|RECORD=41|OwnerIndex=53|IndexInSheet=7|OwnerPartId=-1|Location.X=158|Location.Y=911|Color=8388608|FontID=2|IsHidden=T|Text=SERIES|Name=OTHER
|RECORD=41|OwnerIndex=53|IndexInSheet=8|OwnerPartId=-1|Location.X=158|Location.Y=911|Color=8388608|FontID=2|IsHidden=T|Text=5%|Name=P2
|RECORD=41|OwnerIndex=53|IndexInSheet=9|OwnerPartId=-1|Location.X=158|Location.Y=911|Color=8388608|FontID=2|IsHidden=T|Text=1W|Name=P3
|RECORD=41|OwnerIndex=53|IndexInSheet=10|OwnerPartId=-1|Location.X=158|Location.Y=911|Color=8388608|FontID=2|IsHidden=T|Text=SOD123FL|Name=SIZE
|RECORD=41|OwnerIndex=53|IndexInSheet=11|OwnerPartId=-1|Location.X=158|Location.Y=911|Color=8388608|FontID=2|IsHidden=T|Name=SUB
|RECORD=41|OwnerIndex=53|IndexInSheet=12|OwnerPartId=-1|Location.X=158|Location.Y=911|Color=8388608|FontID=1|IsHidden=T|Text=*|Name=SHEETPART
|RECORD=41|OwnerIndex=53|IndexInSheet=13|OwnerPartId=-1|Location.X=158|Location.Y=911|Color=8388608|FontID=1|IsHidden=T|Text=DIO, ZENER, DFLZ39, 39V, 5%, 1W, SOD123FL|Name=DESC
|RECORD=41|OwnerIndex=53|IndexInSheet=14|OwnerPartId=-1|Location.X=158|Location.Y=911|Color=8388608|FontID=1|IsHidden=T|Text=Digi-Key|Name=Supplier 1|ReadOnlyState=3
|RECORD=41|OwnerIndex=53|IndexInSheet=15|OwnerPartId=-1|Location.X=158|Location.Y=911|Color=8388608|FontID=1|IsHidden=T|Text=DFLZ39-TPMSDKR-ND|Name=Supplier Part Number 1|ReadOnlyState=3
|RECORD=41|OwnerIndex=53|IndexInSheet=16|OwnerPartId=-1|Location.X=179|Location.Y=877|Color=8388608|FontID=2|Text=39V|Name=P1
|RECORD=41|OwnerIndex=53|IndexInSheet=17|OwnerPartId=-1|Location.X=179|Location.Y=865|Color=8388608|FontID=2|Text=DFLZ39|Name=VALUE
|RECORD=2|OwnerIndex=53|OwnerPartId=1|FormalType=1|Electrical=4|PinConglomerate=34|PinLength=20|Location.X=180|Location.Y=900|Name=A|Designator=2|SwapIdPin=2|SwapIDPart=1|PinPropagationDelay=0.000000E+000
|RECORD=2|OwnerIndex=53|OwnerPartId=1|FormalType=1|Electrical=4|PinConglomerate=32|PinLength=20|Location.X=200|Location.Y=900|Name=C|Designator=1|SwapIdPin=1|SwapIDPart=1|PinPropagationDelay=0.000000E+000
|RECORD=13|OwnerIndex=53|IsNotAccesible=T|IndexInSheet=20|OwnerPartId=1|Location.X=183|Location.X_Frac=70000|Location.Y=900|Corner.X=180|Corner.Y=900|LineWidth=1|Color=16711680
|RECORD=13|OwnerIndex=53|IsNotAccesible=T|IndexInSheet=21|OwnerPartId=1|Location.X=200|Location.Y=900|Corner.X=196|Corner.X_Frac=20000|Corner.Y=900|LineWidth=1|Color=16711680
|RECORD=13|OwnerIndex=53|IsNotAccesible=T|IndexInSheet=22|OwnerPartId=1|Location.X=196|Location.X_Frac=20000|Location.Y=907|Location.Y_Frac=50000|Corner.X=193|Corner.X_Frac=70000|Corner.Y=910|LineWidth=1|Color=16711680
|RECORD=13|OwnerIndex=53|IsNotAccesible=T|IndexInSheet=23|OwnerPartId=1|Location.X=198|Location.X_Frac=70000|Location.Y=890|Corner.X=196|Corner.X_Frac=20000|Corner.Y=892|Corner.Y_Frac=50000|LineWidth=1|Color=16711680
|RECORD=13|OwnerIndex=53|IsNotAccesible=T|IndexInSheet=24|OwnerPartId=1|Location.X=196|Location.X_Frac=20000|Location.Y=907|Location.Y_Frac=50000|Corner.X=196|Corner.X_Frac=20000|Corner.Y=892|Corner.Y_Frac=50000|LineWidth=1|Color=16711680
|RECORD=7|OwnerIndex=53|IsNotAccesible=T|IndexInSheet=25|OwnerPartId=1|LineWidth=1|Color=16711680|AreaColor=16711680|IsSolid=T|LocationCount=3|X1=196|X1_Frac=20000|Y1=900|X2=183|X2_Frac=70000|Y2=907|Y2_Frac=50000|X3=183|X3_Frac=70000|Y3=892|Y3_Frac=50000
|RECORD=41|OwnerIndex=53|IndexInSheet=26|OwnerPartId=-1|Location.X=158|Location.Y=911|Color=8388608|FontID=1|IsHidden=T|Text=<VALENTIUM>|Name=VALENTIUM PART NUM
|RECORD=34|OwnerIndex=53|IndexInSheet=-1|OwnerPartId=-1|Location.X=179|Location.Y=911|Color=8388608|FontID=5|Text=D3|Name=Designator|ReadOnlyState=1
|RECORD=41|OwnerIndex=53|IndexInSheet=-1|OwnerPartId=-1|Location.X=158|Location.Y=911|Color=8388608|FontID=2|IsHidden=T|Text=="MFG PART NUM"|Name=Comment
|RECORD=44|OwnerIndex=53
|RECORD=45|OwnerIndex=85|IndexInSheet=-1|Description=SODFL, SOD-123FL, 2-Leads, Body 1.65x3.70mm, IPC Medium Density|UseComponentLibrary=T|ModelName=SODFL370X135-2N|ModelType=PCBLIB|DatafileCount=1|ModelDatafileEntity0=SODFL370X135-2N|ModelDatafileKind0=PCBLib|IsCurrent=T|DatalinksLocked=T|DatabaseDatalinksLocked=T|IntegratedModel=T|DatabaseModel=T
|RECORD=46|OwnerIndex=86
|RECORD=48|OwnerIndex=86
|RECORD=1|LibReference=CAP_0805_10UF_25V|ComponentDescription=CAP, CER, 10.UF, 25V, 10%, X5R, 0805|PartCount=2|DisplayModeCount=1|IndexInSheet=43|OwnerPartId=-1|Location.X=310|Location.Y=810|CurrentPartId=1|LibraryPath=*|SourceLibraryName=Capacitors.IntLib|TargetFileName=*|AreaColor=11599871|Color=128|PartIDLocked=F|DesignItemId=CAP_0805_10UF_25V|AllPinCount=2
|RECORD=41|OwnerIndex=89|OwnerPartId=-1|Location.X=310|Location.Y=810|Color=8388608|FontID=2|IsHidden=T|Text=TAIYO YUDEN|Name=MFG NAME
|RECORD=41|OwnerIndex=89|IndexInSheet=1|OwnerPartId=-1|Location.X=310|Location.Y=810|Color=8388608|FontID=2|IsHidden=T|Text=TMK212BBJ106KG-T|Name=MFG PART NUM
|RECORD=41|OwnerIndex=89|IndexInSheet=2|OwnerPartId=-1|Location.X=310|Location.Y=810|Color=8388608|FontID=2|IsHidden=T|Text=10/23/2013|Name=MODIFY DATE
|RECORD=41|OwnerIndex=89|IndexInSheet=3|OwnerPartId=-1|Location.X=310|Location.Y=810|Color=8388608|FontID=2|IsHidden=T|Text=CAP, CER|Name=CATEGORY
|RECORD=41|OwnerIndex=89|IndexInSheet=4|OwnerPartId=-1|Location.X=308|Location.Y=822|Location.Y_Frac=50000|Color=8388608|FontID=2|IsHidden=T|Text=4/11/2006 3:37:28 PM|Name=Date
|RECORD=41|OwnerIndex=89|IndexInSheet=5|OwnerPartId=-1|Location.X=316|Location.Y=884|Location.Y_Frac=48252|Color=8388608|FontID=2|IsHidden=T|Text=*|Name=SHEETPART
|RECORD=41|OwnerIndex=89|IndexInSheet=6|OwnerPartId=-1|Location.X=316|Location.Y=884|Location.Y_Frac=48252|Color=8388608|FontID=2|IsHidden=T|Text=10%|Name=P1
|RECORD=41|OwnerIndex=89|IndexInSheet=7|OwnerPartId=-1|Location.X=316|Location.Y=884|Location.Y_Frac=48252|Color=8388608|FontID=2|IsHidden=T|Text=85C|Name=MAXTEMP
|RECORD=41|OwnerIndex=89|IndexInSheet=8|OwnerPartId=-1|Location.X=316|Location.Y=884|Location.Y_Frac=48252|Color=8388608|FontID=2|IsHidden=T|Text=-55C|Name=MINTEMP
|RECORD=41|OwnerIndex=89|IndexInSheet=9|OwnerPartId=-1|Location.X=316|Location.Y=884|Location.Y_Frac=48252|Color=8388608|FontID=2|IsHidden=T|Name=OTHER
|RECORD=41|OwnerIndex=89|IndexInSheet=10|OwnerPartId=-1|Location.X=316|Location.Y=884|Location.Y_Frac=48252|Color=8388608|FontID=2|IsHidden=T|Text=25V|Name=P2
|RECORD=41|OwnerIndex=89|IndexInSheet=11|OwnerPartId=-1|Location.X=316|Location.Y=884|Location.Y_Frac=48252|Color=8388608|FontID=2|IsHidden=T|Text=X5R|Name=P3
|RECORD=41|OwnerIndex=89|IndexInSheet=12|OwnerPartId=-1|Location.X=316|Location.Y=884|Location.Y_Frac=48252|Color=8388608|FontID=2|IsHidden=T|Text=0805|Name=Size
|RECORD=41|OwnerIndex=89|IndexInSheet=13|OwnerPartId=-1|Location.X=316|Location.Y=884|Location.Y_Frac=48252|Color=8388608|FontID=2|IsHidden=T|Name=SUB
|RECORD=41|OwnerIndex=89|IndexInSheet=14|OwnerPartId=-1|Location.X=316|Location.Y=884|Location.Y_Frac=48252|Color=8388608|FontID=1|IsHidden=T|Text=CAP, CER, 10.UF, 10V, 10%, X5R, 0805|Name=DESC
|RECORD=41|OwnerIndex=89|IndexInSheet=15|OwnerPartId=-1|Location.X=316|Location.Y=883|Location.Y_Frac=98252|Color=8388608|FontID=1|IsHidden=T|Text=MOUSER|Name=Supplier 1|ReadOnlyState=1
|RECORD=41|OwnerIndex=89|IndexInSheet=16|OwnerPartId=-1|Location.X=316|Location.Y=883|Location.Y_Frac=98252|Color=8388608|FontID=1|IsHidden=T|Text=963-TMK212BBJ106KG-T|Name=Supplier Part Number 1|ReadOnlyState=1
|RECORD=41|OwnerIndex=89|IndexInSheet=17|OwnerPartId=-1|Location.X=340|Location.Y=840|Color=8388608|FontID=2|Text=10uF|Name=VALUE
|RECORD=2|OwnerIndex=89|OwnerPartId=1|FormalType=1|Electrical=4|PinConglomerate=35|PinLength=10|Location.X=330|Location.Y=840|Name=2|Designator=2|SwapIdPin=2|SwapIDPart=1|PinPropagationDelay=0.000000E+000
|RECORD=2|OwnerIndex=89|OwnerPartId=1|FormalType=1|Electrical=4|PinConglomerate=33|PinLength=10|Location.X=330|Location.Y=850|Name=1|Designator=1|SwapIdPin=1|SwapIDPart=1|PinPropagationDelay=0.000000E+000
|RECORD=13|OwnerIndex=89|IsNotAccesible=T|IndexInSheet=20|OwnerPartId=1|Location.X=330|Location.Y=842|Location.Y_Frac=50000|Corner.X=330|Corner.Y=840|LineWidth=1|Color=16711680
|RECORD=13|OwnerIndex=89|IsNotAccesible=T|IndexInSheet=21|OwnerPartId=1|Location.X=330|Location.Y=850|Corner.X=330|Corner.Y=847|Corner.Y_Frac=50000|LineWidth=1|Color=16711680
|RECORD=13|OwnerIndex=89|IsNotAccesible=T|IndexInSheet=22|OwnerPartId=1|Location.X=335|Location.Y=842|Location.Y_Frac=50000|Corner.X=325|Corner.Y=842|Corner.Y_Frac=50000|LineWidth=1|Color=16711680
|RECORD=13|OwnerIndex=89|IsNotAccesible=T|IndexInSheet=23|OwnerPartId=1|Location.X=335|Location.Y=847|Location.Y_Frac=50000|Corner.X=325|Corner.Y=847|Corner.Y_Frac=50000|LineWidth=1|Color=16711680
|RECORD=41|OwnerIndex=89|IndexInSheet=24|OwnerPartId=-1|Location.X=316|Location.Y=883|Location.Y_Frac=98951|Color=8388608|FontID=1|IsHidden=T|Text=<VALENTIUM>|Name=VALENTIUM PART NUM
|RECORD=34|OwnerIndex=89|IndexInSheet=-1|OwnerPartId=-1|Location.X=340|Location.Y=850|Color=8388608|FontID=5|Text=C1|Name=Designator|ReadOnlyState=1
|RECORD=41|OwnerIndex=89|IndexInSheet=-1|OwnerPartId=-1|Location.X=337|Location.X_Frac=50000|Location.Y=805|Color=8388608|FontID=2|IsHidden=T|Text=CAP_0805_10UF_25V|Name=Comment
|RECORD=44|OwnerIndex=89
|RECORD=45|OwnerIndex=119|IndexInSheet=-1|Description=Chip Capacitor, 0805, 2-Leads, Body 2.00x1.25mm, IPC Medium Density|UseComponentLibrary=T|ModelName=CAPC2012X14N|ModelType=PCBLIB|DatafileCount=1|ModelDatafileEntity0=CAPC2012X14N|ModelDatafileKind0=PCBLib|IsCurrent=T|DatalinksLocked=T|DatabaseDatalinksLocked=T|IntegratedModel=T|DatabaseModel=T
|RECORD=46|OwnerIndex=120
|RECORD=48|OwnerIndex=120
|RECORD=1|LibReference=CAP_0805_10UF_25V|ComponentDescription=CAP, CER, 10.UF, 25V, 10%, X5R, 0805|PartCount=2|DisplayModeCount=1|IndexInSheet=44|OwnerPartId=-1|Location.X=510|Location.Y=890|CurrentPartId=1|LibraryPath=*|SourceLibraryName=Capacitors.IntLib|TargetFileName=*|AreaColor=11599871|Color=128|PartIDLocked=F|DesignItemId=CAP_0805_10UF_25V|AllPinCount=2
|RECORD=41|OwnerIndex=123|OwnerPartId=-1|Location.X=510|Location.Y=890|Color=8388608|FontID=2|IsHidden=T|Text=TAIYO YUDEN|Name=MFG NAME
|RECORD=41|OwnerIndex=123|IndexInSheet=1|OwnerPartId=-1|Location.X=510|Location.Y=890|Color=8388608|FontID=2|IsHidden=T|Text=TMK212BBJ106KG-T|Name=MFG PART NUM
|RECORD=41|OwnerIndex=123|IndexInSheet=2|OwnerPartId=-1|Location.X=510|Location.Y=890|Color=8388608|FontID=2|IsHidden=T|Text=10/23/2013|Name=MODIFY DATE
|RECORD=41|OwnerIndex=123|IndexInSheet=3|OwnerPartId=-1|Location.X=510|Location.Y=890|Color=8388608|FontID=2|IsHidden=T|Text=CAP, CER|Name=CATEGORY
|RECORD=41|OwnerIndex=123|IndexInSheet=4|OwnerPartId=-1|Location.X=508|Location.Y=902|Location.Y_Frac=50000|Color=8388608|FontID=2|IsHidden=T|Text=4/11/2006 3:37:28 PM|Name=Date
|RECORD=41|OwnerIndex=123|IndexInSheet=5|OwnerPartId=-1|Location.X=516|Location.Y=964|Location.Y_Frac=48252|Color=8388608|FontID=2|IsHidden=T|Text=*|Name=SHEETPART
|RECORD=41|OwnerIndex=123|IndexInSheet=6|OwnerPartId=-1|Location.X=516|Location.Y=964|Location.Y_Frac=48252|Color=8388608|FontID=2|IsHidden=T|Text=10%|Name=P1
|RECORD=41|OwnerIndex=123|IndexInSheet=7|OwnerPartId=-1|Location.X=516|Location.Y=964|Location.Y_Frac=48252|Color=8388608|FontID=2|IsHidden=T|Text=85C|Name=MAXTEMP
|RECORD=41|OwnerIndex=123|IndexInSheet=8|OwnerPartId=-1|Location.X=516|Location.Y=964|Location.Y_Frac=48252|Color=8388608|FontID=2|IsHidden=T|Text=-55C|Name=MINTEMP
|RECORD=41|OwnerIndex=123|IndexInSheet=9|OwnerPartId=-1|Location.X=516|Location.Y=964|Location.Y_Frac=48252|Color=8388608|FontID=2|IsHidden=T|Name=OTHER
|RECORD=41|OwnerIndex=123|IndexInSheet=10|OwnerPartId=-1|Location.X=516|Location.Y=964|Location.Y_Frac=48252|Color=8388608|FontID=2|IsHidden=T|Text=25V|Name=P2
|RECORD=41|OwnerIndex=123|IndexInSheet=11|OwnerPartId=-1|Location.X=516|Location.Y=964|Location.Y_Frac=48252|Color=8388608|FontID=2|IsHidden=T|Text=X5R|Name=P3
|RECORD=41|OwnerIndex=123|IndexInSheet=12|OwnerPartId=-1|Location.X=516|Location.Y=964|Location.Y_Frac=48252|Color=8388608|FontID=2|IsHidden=T|Text=0805|Name=Size
|RECORD=41|OwnerIndex=123|IndexInSheet=13|OwnerPartId=-1|Location.X=516|Location.Y=964|Location.Y_Frac=48252|Color=8388608|FontID=2|IsHidden=T|Name=SUB
|RECORD=41|OwnerIndex=123|IndexInSheet=14|OwnerPartId=-1|Location.X=516|Location.Y=964|Location.Y_Frac=48252|Color=8388608|FontID=1|IsHidden=T|Text=CAP, CER, 10.UF, 10V, 10%, X5R, 0805|Name=DESC
|RECORD=41|OwnerIndex=123|IndexInSheet=15|OwnerPartId=-1|Location.X=516|Location.Y=963|Location.Y_Frac=98252|Color=8388608|FontID=1|IsHidden=T|Text=MOUSER|Name=Supplier 1|ReadOnlyState=1
|RECORD=41|OwnerIndex=123|IndexInSheet=16|OwnerPartId=-1|Location.X=516|Location.Y=963|Location.Y_Frac=98252|Color=8388608|FontID=1|IsHidden=T|Text=963-TMK212BBJ106KG-T|Name=Supplier Part Number 1|ReadOnlyState=1
|RECORD=41|OwnerIndex=123|IndexInSheet=17|OwnerPartId=-1|Location.X=540|Location.Y=920|Color=8388608|FontID=2|Text=10uF|Name=VALUE
|RECORD=2|OwnerIndex=123|OwnerPartId=1|FormalType=1|Electrical=4|PinConglomerate=35|PinLength=10|Location.X=530|Location.Y=920|Name=2|Designator=2|SwapIdPin=2|SwapIDPart=1|PinPropagationDelay=0.000000E+000
|RECORD=2|OwnerIndex=123|OwnerPartId=1|FormalType=1|Electrical=4|PinConglomerate=33|PinLength=10|Location.X=530|Location.Y=930|Name=1|Designator=1|SwapIdPin=1|SwapIDPart=1|PinPropagationDelay=0.000000E+000
|RECORD=13|OwnerIndex=123|IsNotAccesible=T|IndexInSheet=20|OwnerPartId=1|Location.X=530|Location.Y=922|Location.Y_Frac=50000|Corner.X=530|Corner.Y=920|LineWidth=1|Color=16711680
|RECORD=13|OwnerIndex=123|IsNotAccesible=T|IndexInSheet=21|OwnerPartId=1|Location.X=530|Location.Y=930|Corner.X=530|Corner.Y=927|Corner.Y_Frac=50000|LineWidth=1|Color=16711680
|RECORD=13|OwnerIndex=123|IsNotAccesible=T|IndexInSheet=22|OwnerPartId=1|Location.X=535|Location.Y=922|Location.Y_Frac=50000|Corner.X=525|Corner.Y=922|Corner.Y_Frac=50000|LineWidth=1|Color=16711680
|RECORD=13|OwnerIndex=123|IsNotAccesible=T|IndexInSheet=23|OwnerPartId=1|Location.X=535|Location.Y=927|Location.Y_Frac=50000|Corner.X=525|Corner.Y=927|Corner.Y_Frac=50000|LineWidth=1|Color=16711680
|RECORD=41|OwnerIndex=123|IndexInSheet=24|OwnerPartId=-1|Location.X=516|Location.Y=963|Location.Y_Frac=98951|Color=8388608|FontID=1|IsHidden=T|Text=<VALENTIUM>|Name=VALENTIUM PART NUM
|RECORD=34|OwnerIndex=123|IndexInSheet=-1|OwnerPartId=-1|Location.X=540|Location.Y=930|Color=8388608|FontID=5|Text=C6|Name=Designator|ReadOnlyState=1
|RECORD=41|OwnerIndex=123|IndexInSheet=-1|OwnerPartId=-1|Location.X=537|Location.X_Frac=50000|Location.Y=885|Color=8388608|FontID=2|IsHidden=T|Text=CAP_0805_10UF_25V|Name=Comment
|RECORD=44|OwnerIndex=123
|RECORD=45|OwnerIndex=153|IndexInSheet=-1|Description=Chip Capacitor, 0805, 2-Leads, Body 2.00x1.25mm, IPC Medium Density|UseComponentLibrary=T|ModelName=CAPC2012X14N|ModelType=PCBLIB|DatafileCount=1|ModelDatafileEntity0=CAPC2012X14N|ModelDatafileKind0=PCBLib|IsCurrent=T|DatalinksLocked=T|DatabaseDatalinksLocked=T|IntegratedModel=T|DatabaseModel=T
|RECORD=46|OwnerIndex=154
|RECORD=48|OwnerIndex=154
|RECORD=1|LibReference=CAP_0805_10UF_25V|ComponentDescription=CAP, CER, 10.UF, 25V, 10%, X5R, 0805|PartCount=2|DisplayModeCount=1|IndexInSheet=45|OwnerPartId=-1|Location.X=1010|Location.Y=760|CurrentPartId=1|LibraryPath=*|SourceLibraryName=Capacitors.IntLib|TargetFileName=*|AreaColor=11599871|Color=128|PartIDLocked=F|DesignItemId=CAP_0805_10UF_25V|AllPinCount=2
|RECORD=41|OwnerIndex=157|OwnerPartId=-1|Location.X=1010|Location.Y=760|Color=8388608|FontID=2|IsHidden=T|Text=TAIYO YUDEN|Name=MFG NAME
|RECORD=41|OwnerIndex=157|IndexInSheet=1|OwnerPartId=-1|Location.X=1010|Location.Y=760|Color=8388608|FontID=2|IsHidden=T|Text=TMK212BBJ106KG-T|Name=MFG PART NUM
|RECORD=41|OwnerIndex=157|IndexInSheet=2|OwnerPartId=-1|Location.X=1010|Location.Y=760|Color=8388608|FontID=2|IsHidden=T|Text=10/23/2013|Name=MODIFY DATE
|RECORD=41|OwnerIndex=157|IndexInSheet=3|OwnerPartId=-1|Location.X=1010|Location.Y=760|Color=8388608|FontID=2|IsHidden=T|Text=CAP, CER|Name=CATEGORY
|RECORD=41|OwnerIndex=157|IndexInSheet=4|OwnerPartId=-1|Location.X=1008|Location.Y=772|Location.Y_Frac=50000|Color=8388608|FontID=2|IsHidden=T|Text=4/11/2006 3:37:28 PM|Name=Date
|RECORD=41|OwnerIndex=157|IndexInSheet=5|OwnerPartId=-1|Location.X=1016|Location.Y=834|Location.Y_Frac=48252|Color=8388608|FontID=2|IsHidden=T|Text=*|Name=SHEETPART
|RECORD=41|OwnerIndex=157|IndexInSheet=6|OwnerPartId=-1|Location.X=1016|Location.Y=834|Location.Y_Frac=48252|Color=8388608|FontID=2|IsHidden=T|Text=10%|Name=P1
|RECORD=41|OwnerIndex=157|IndexInSheet=7|OwnerPartId=-1|Location.X=1016|Location.Y=834|Location.Y_Frac=48252|Color=8388608|FontID=2|IsHidden=T|Text=85C|Name=MAXTEMP
|RECORD=41|OwnerIndex=157|IndexInSheet=8|OwnerPartId=-1|Location.X=1016|Location.Y=834|Location.Y_Frac=48252|Color=8388608|FontID=2|IsHidden=T|Text=-55C|Name=MINTEMP
|RECORD=41|OwnerIndex=157|IndexInSheet=9|OwnerPartId=-1|Location.X=1016|Location.Y=834|Location.Y_Frac=48252|Color=8388608|FontID=2|IsHidden=T|Name=OTHER
|RECORD=41|OwnerIndex=157|IndexInSheet=10|OwnerPartId=-1|Location.X=1016|Location.Y=834|Location.Y_Frac=48252|Color=8388608|FontID=2|IsHidden=T|Text=25V|Name=P2
|RECORD=41|OwnerIndex=157|IndexInSheet=11|OwnerPartId=-1|Location.X=1016|Location.Y=834|Location.Y_Frac=48252|Color=8388608|FontID=2|IsHidden=T|Text=X5R|Name=P3
|RECORD=41|OwnerIndex=157|IndexInSheet=12|OwnerPartId=-1|Location.X=1016|Location.Y=834|Location.Y_Frac=48252|Color=8388608|FontID=2|IsHidden=T|Text=0805|Name=Size
|RECORD=41|OwnerIndex=157|IndexInSheet=13|OwnerPartId=-1|Location.X=1016|Location.Y=834|Location.Y_Frac=48252|Color=8388608|FontID=2|IsHidden=T|Name=SUB
|RECORD=41|OwnerIndex=157|IndexInSheet=14|OwnerPartId=-1|Location.X=1016|Location.Y=834|Location.Y_Frac=48252|Color=8388608|FontID=1|IsHidden=T|Text=CAP, CER, 10.UF, 10V, 10%, X5R, 0805|Name=DESC
|RECORD=41|OwnerIndex=157|IndexInSheet=15|OwnerPartId=-1|Location.X=1016|Location.Y=833|Location.Y_Frac=98252|Color=8388608|FontID=1|IsHidden=T|Text=MOUSER|Name=Supplier 1|ReadOnlyState=1
|RECORD=41|OwnerIndex=157|IndexInSheet=16|OwnerPartId=-1|Location.X=1016|Location.Y=833|Location.Y_Frac=98252|Color=8388608|FontID=1|IsHidden=T|Text=963-TMK212BBJ106KG-T|Name=Supplier Part Number 1|ReadOnlyState=1
|RECORD=41|OwnerIndex=157|IndexInSheet=17|OwnerPartId=-1|Location.X=1040|Location.Y=790|Color=8388608|FontID=2|Text=10uF|Name=VALUE
|RECORD=2|OwnerIndex=157|OwnerPartId=1|FormalType=1|Electrical=4|PinConglomerate=35|PinLength=10|Location.X=1030|Location.Y=790|Name=2|Designator=2|SwapIdPin=2|SwapIDPart=1|PinPropagationDelay=0.000000E+000
|RECORD=2|OwnerIndex=157|OwnerPartId=1|FormalType=1|Electrical=4|PinConglomerate=33|PinLength=10|Location.X=1030|Location.Y=800|Name=1|Designator=1|SwapIdPin=1|SwapIDPart=1|PinPropagationDelay=0.000000E+000
|RECORD=13|OwnerIndex=157|IsNotAccesible=T|IndexInSheet=20|OwnerPartId=1|Location.X=1030|Location.Y=792|Location.Y_Frac=50000|Corner.X=1030|Corner.Y=790|LineWidth=1|Color=16711680
|RECORD=13|OwnerIndex=157|IsNotAccesible=T|IndexInSheet=21|OwnerPartId=1|Location.X=1030|Location.Y=800|Corner.X=1030|Corner.Y=797|Corner.Y_Frac=50000|LineWidth=1|Color=16711680
|RECORD=13|OwnerIndex=157|IsNotAccesible=T|IndexInSheet=22|OwnerPartId=1|Location.X=1035|Location.Y=792|Location.Y_Frac=50000|Corner.X=1025|Corner.Y=792|Corner.Y_Frac=50000|LineWidth=1|Color=16711680
|RECORD=13|OwnerIndex=157|IsNotAccesible=T|IndexInSheet=23|OwnerPartId=1|Location.X=1035|Location.Y=797|Location.Y_Frac=50000|Corner.X=1025|Corner.Y=797|Corner.Y_Frac=50000|LineWidth=1|Color=16711680
|RECORD=41|OwnerIndex=157|IndexInSheet=24|OwnerPartId=-1|Location.X=1016|Location.Y=833|Location.Y_Frac=98951|Color=8388608|FontID=1|IsHidden=T|Text=<VALENTIUM>|Name=VALENTIUM PART NUM
|RECORD=34|OwnerIndex=157|IndexInSheet=-1|OwnerPartId=-1|Location.X=1040|Location.Y=800|Color=8388608|FontID=5|Text=C14|Name=Designator|ReadOnlyState=1
|RECORD=41|OwnerIndex=157|IndexInSheet=-1|OwnerPartId=-1|Location.X=1037|Location.X_Frac=50000|Location.Y=755|Color=8388608|FontID=2|IsHidden=T|Text=CAP_0805_10UF_25V|Name=Comment
|RECORD=44|OwnerIndex=157
|RECORD=45|OwnerIndex=187|IndexInSheet=-1|Description=Chip Capacitor, 0805, 2-Leads, Body 2.00x1.25mm, IPC Medium Density|UseComponentLibrary=T|ModelName=CAPC2012X14N|ModelType=PCBLIB|DatafileCount=1|ModelDatafileEntity0=CAPC2012X14N|ModelDatafileKind0=PCBLib|IsCurrent=T|DatalinksLocked=T|DatabaseDatalinksLocked=T|IntegratedModel=T|DatabaseModel=T
|RECORD=46|OwnerIndex=188
|RECORD=48|OwnerIndex=188
|RECORD=1|LibReference=CAP_0805_10UF_25V|ComponentDescription=CAP, CER, 10.UF, 25V, 10%, X5R, 0805|PartCount=2|DisplayModeCount=1|IndexInSheet=46|OwnerPartId=-1|Location.X=960|Location.Y=760|CurrentPartId=1|LibraryPath=*|SourceLibraryName=Capacitors.IntLib|TargetFileName=*|AreaColor=11599871|Color=128|PartIDLocked=F|DesignItemId=CAP_0805_10UF_25V|AllPinCount=2
|RECORD=41|OwnerIndex=191|OwnerPartId=-1|Location.X=960|Location.Y=760|Color=8388608|FontID=2|IsHidden=T|Text=TAIYO YUDEN|Name=MFG NAME
|RECORD=41|OwnerIndex=191|IndexInSheet=1|OwnerPartId=-1|Location.X=960|Location.Y=760|Color=8388608|FontID=2|IsHidden=T|Text=TMK212BBJ106KG-T|Name=MFG PART NUM
|RECORD=41|OwnerIndex=191|IndexInSheet=2|OwnerPartId=-1|Location.X=960|Location.Y=760|Color=8388608|FontID=2|IsHidden=T|Text=10/23/2013|Name=MODIFY DATE
|RECORD=41|OwnerIndex=191|IndexInSheet=3|OwnerPartId=-1|Location.X=960|Location.Y=760|Color=8388608|FontID=2|IsHidden=T|Text=CAP, CER|Name=CATEGORY
|RECORD=41|OwnerIndex=191|IndexInSheet=4|OwnerPartId=-1|Location.X=958|Location.Y=772|Location.Y_Frac=50000|Color=8388608|FontID=2|IsHidden=T|Text=4/11/2006 3:37:28 PM|Name=Date
|RECORD=41|OwnerIndex=191|IndexInSheet=5|OwnerPartId=-1|Location.X=966|Location.Y=834|Location.Y_Frac=48252|Color=8388608|FontID=2|IsHidden=T|Text=*|Name=SHEETPART
|RECORD=41|OwnerIndex=191|IndexInSheet=6|OwnerPartId=-1|Location.X=966|Location.Y=834|Location.Y_Frac=48252|Color=8388608|FontID=2|IsHidden=T|Text=10%|Name=P1
|RECORD=41|OwnerIndex=191|IndexInSheet=7|OwnerPartId=-1|Location.X=966|Location.Y=834|Location.Y_Frac=48252|Color=8388608|FontID=2|IsHidden=T|Text=85C|Name=MAXTEMP
|RECORD=41|OwnerIndex=191|IndexInSheet=8|OwnerPartId=-1|Location.X=966|Location.Y=834|Location.Y_Frac=48252|Color=8388608|FontID=2|IsHidden=T|Text=-55C|Name=MINTEMP
|RECORD=41|OwnerIndex=191|IndexInSheet=9|OwnerPartId=-1|Location.X=966|Location.Y=834|Location.Y_Frac=48252|Color=8388608|FontID=2|IsHidden=T|Name=OTHER
|RECORD=41|OwnerIndex=191|IndexInSheet=10|OwnerPartId=-1|Location.X=966|Location.Y=834|Location.Y_Frac=48252|Color=8388608|FontID=2|IsHidden=T|Text=25V|Name=P2
|RECORD=41|OwnerIndex=191|IndexInSheet=11|OwnerPartId=-1|Location.X=966|Location.Y=834|Location.Y_Frac=48252|Color=8388608|FontID=2|IsHidden=T|Text=X5R|Name=P3
|RECORD=41|OwnerIndex=191|IndexInSheet=12|OwnerPartId=-1|Location.X=966|Location.Y=834|Location.Y_Frac=48252|Color=8388608|FontID=2|IsHidden=T|Text=0805|Name=Size
|RECORD=41|OwnerIndex=191|IndexInSheet=13|OwnerPartId=-1|Location.X=966|Location.Y=834|Location.Y_Frac=48252|Color=8388608|FontID=2|IsHidden=T|Name=SUB
|RECORD=41|OwnerIndex=191|IndexInSheet=14|OwnerPartId=-1|Location.X=966|Location.Y=834|Location.Y_Frac=48252|Color=8388608|FontID=1|IsHidden=T|Text=CAP, CER, 10.UF, 10V, 10%, X5R, 0805|Name=DESC
|RECORD=41|OwnerIndex=191|IndexInSheet=15|OwnerPartId=-1|Location.X=966|Location.Y=833|Location.Y_Frac=98252|Color=8388608|FontID=1|IsHidden=T|Text=MOUSER|Name=Supplier 1|ReadOnlyState=1
|RECORD=41|OwnerIndex=191|IndexInSheet=16|OwnerPartId=-1|Location.X=966|Location.Y=833|Location.Y_Frac=98252|Color=8388608|FontID=1|IsHidden=T|Text=963-TMK212BBJ106KG-T|Name=Supplier Part Number 1|ReadOnlyState=1
|RECORD=41|OwnerIndex=191|IndexInSheet=17|OwnerPartId=-1|Location.X=990|Location.Y=790|Color=8388608|FontID=2|Text=10uF|Name=VALUE
|RECORD=2|OwnerIndex=191|OwnerPartId=1|FormalType=1|Electrical=4|PinConglomerate=35|PinLength=10|Location.X=980|Location.Y=790|Name=2|Designator=2|SwapIdPin=2|SwapIDPart=1|PinPropagationDelay=0.000000E+000
|RECORD=2|OwnerIndex=191|OwnerPartId=1|FormalType=1|Electrical=4|PinConglomerate=33|PinLength=10|Location.X=980|Location.Y=800|Name=1|Designator=1|SwapIdPin=1|SwapIDPart=1|PinPropagationDelay=0.000000E+000
|RECORD=13|OwnerIndex=191|IsNotAccesible=T|IndexInSheet=20|OwnerPartId=1|Location.X=980|Location.Y=792|Location.Y_Frac=50000|Corner.X=980|Corner.Y=790|LineWidth=1|Color=16711680
|RECORD=13|OwnerIndex=191|IsNotAccesible=T|IndexInSheet=21|OwnerPartId=1|Location.X=980|Location.Y=800|Corner.X=980|Corner.Y=797|Corner.Y_Frac=50000|LineWidth=1|Color=16711680
|RECORD=13|OwnerIndex=191|IsNotAccesible=T|IndexInSheet=22|OwnerPartId=1|Location.X=985|Location.Y=792|Location.Y_Frac=50000|Corner.X=975|Corner.Y=792|Corner.Y_Frac=50000|LineWidth=1|Color=16711680
|RECORD=13|OwnerIndex=191|IsNotAccesible=T|IndexInSheet=23|OwnerPartId=1|Location.X=985|Location.Y=797|Location.Y_Frac=50000|Corner.X=975|Corner.Y=797|Corner.Y_Frac=50000|LineWidth=1|Color=16711680
|RECORD=41|OwnerIndex=191|IndexInSheet=24|OwnerPartId=-1|Location.X=966|Location.Y=833|Location.Y_Frac=98951|Color=8388608|FontID=1|IsHidden=T|Text=<VALENTIUM>|Name=VALENTIUM PART NUM
|RECORD=34|OwnerIndex=191|IndexInSheet=-1|OwnerPartId=-1|Location.X=990|Location.Y=800|Color=8388608|FontID=5|Text=C13|Name=Designator|ReadOnlyState=1
|RECORD=41|OwnerIndex=191|IndexInSheet=-1|OwnerPartId=-1|Location.X=987|Location.X_Frac=50000|Location.Y=755|Color=8388608|FontID=2|IsHidden=T|Text=CAP_0805_10UF_25V|Name=Comment
|RECORD=44|OwnerIndex=191
|RECORD=45|OwnerIndex=221|IndexInSheet=-1|Description=Chip Capacitor, 0805, 2-Leads, Body 2.00x1.25mm, IPC Medium Density|UseComponentLibrary=T|ModelName=CAPC2012X14N|ModelType=PCBLIB|DatafileCount=1|ModelDatafileEntity0=CAPC2012X14N|ModelDatafileKind0=PCBLib|IsCurrent=T|DatalinksLocked=T|DatabaseDatalinksLocked=T|IntegratedModel=T|DatabaseModel=T
|RECORD=46|OwnerIndex=222
|RECORD=48|OwnerIndex=222
|RECORD=1|LibReference=CAP_0805_10UF_25V|ComponentDescription=CAP, CER, 10.UF, 25V, 10%, X5R, 0805|PartCount=2|DisplayModeCount=1|IndexInSheet=47|OwnerPartId=-1|Location.X=510|Location.Y=490|CurrentPartId=1|LibraryPath=*|SourceLibraryName=Capacitors.IntLib|TargetFileName=*|AreaColor=11599871|Color=128|PartIDLocked=F|DesignItemId=CAP_0805_10UF_25V|AllPinCount=2
|RECORD=41|OwnerIndex=225|OwnerPartId=-1|Location.X=510|Location.Y=490|Color=8388608|FontID=2|IsHidden=T|Text=TAIYO YUDEN|Name=MFG NAME
|RECORD=41|OwnerIndex=225|IndexInSheet=1|OwnerPartId=-1|Location.X=510|Location.Y=490|Color=8388608|FontID=2|IsHidden=T|Text=TMK212BBJ106KG-T|Name=MFG PART NUM
|RECORD=41|OwnerIndex=225|IndexInSheet=2|OwnerPartId=-1|Location.X=510|Location.Y=490|Color=8388608|FontID=2|IsHidden=T|Text=10/23/2013|Name=MODIFY DATE
|RECORD=41|OwnerIndex=225|IndexInSheet=3|OwnerPartId=-1|Location.X=510|Location.Y=490|Color=8388608|FontID=2|IsHidden=T|Text=CAP, CER|Name=CATEGORY
|RECORD=41|OwnerIndex=225|IndexInSheet=4|OwnerPartId=-1|Location.X=508|Location.Y=502|Location.Y_Frac=50000|Color=8388608|FontID=2|IsHidden=T|Text=4/11/2006 3:37:28 PM|Name=Date
|RECORD=41|OwnerIndex=225|IndexInSheet=5|OwnerPartId=-1|Location.X=516|Location.Y=564|Location.Y_Frac=48252|Color=8388608|FontID=2|IsHidden=T|Text=*|Name=SHEETPART
|RECORD=41|OwnerIndex=225|IndexInSheet=6|OwnerPartId=-1|Location.X=516|Location.Y=564|Location.Y_Frac=48252|Color=8388608|FontID=2|IsHidden=T|Text=10%|Name=P1
|RECORD=41|OwnerIndex=225|IndexInSheet=7|OwnerPartId=-1|Location.X=516|Location.Y=564|Location.Y_Frac=48252|Color=8388608|FontID=2|IsHidden=T|Text=85C|Name=MAXTEMP
|RECORD=41|OwnerIndex=225|IndexInSheet=8|OwnerPartId=-1|Location.X=516|Location.Y=564|Location.Y_Frac=48252|Color=8388608|FontID=2|IsHidden=T|Text=-55C|Name=MINTEMP
|RECORD=41|OwnerIndex=225|IndexInSheet=9|OwnerPartId=-1|Location.X=516|Location.Y=564|Location.Y_Frac=48252|Color=8388608|FontID=2|IsHidden=T|Name=OTHER
|RECORD=41|OwnerIndex=225|IndexInSheet=10|OwnerPartId=-1|Location.X=516|Location.Y=564|Location.Y_Frac=48252|Color=8388608|FontID=2|IsHidden=T|Text=25V|Name=P2
|RECORD=41|OwnerIndex=225|IndexInSheet=11|OwnerPartId=-1|Location.X=516|Location.Y=564|Location.Y_Frac=48252|Color=8388608|FontID=2|IsHidden=T|Text=X5R|Name=P3
|RECORD=41|OwnerIndex=225|IndexInSheet=12|OwnerPartId=-1|Location.X=516|Location.Y=564|Location.Y_Frac=48252|Color=8388608|FontID=2|IsHidden=T|Text=0805|Name=Size
|RECORD=41|OwnerIndex=225|IndexInSheet=13|OwnerPartId=-1|Location.X=516|Location.Y=564|Location.Y_Frac=48252|Color=8388608|FontID=2|IsHidden=T|Name=SUB
|RECORD=41|OwnerIndex=225|IndexInSheet=14|OwnerPartId=-1|Location.X=516|Location.Y=564|Location.Y_Frac=48252|Color=8388608|FontID=1|IsHidden=T|Text=CAP, CER, 10.UF, 10V, 10%, X5R, 0805|Name=DESC
|RECORD=41|OwnerIndex=225|IndexInSheet=15|OwnerPartId=-1|Location.X=516|Location.Y=563|Location.Y_Frac=98252|Color=8388608|FontID=1|IsHidden=T|Text=MOUSER|Name=Supplier 1|ReadOnlyState=1
|RECORD=41|OwnerIndex=225|IndexInSheet=16|OwnerPartId=-1|Location.X=516|Location.Y=563|Location.Y_Frac=98252|Color=8388608|FontID=1|IsHidden=T|Text=963-TMK212BBJ106KG-T|Name=Supplier Part Number 1|ReadOnlyState=1
|RECORD=41|OwnerIndex=225|IndexInSheet=17|OwnerPartId=-1|Location.X=540|Location.Y=520|Color=8388608|FontID=2|Text=10uF|Name=VALUE
|RECORD=2|OwnerIndex=225|OwnerPartId=1|FormalType=1|Electrical=4|PinConglomerate=35|PinLength=10|Location.X=530|Location.Y=520|Name=2|Designator=2|SwapIdPin=2|SwapIDPart=1|PinPropagationDelay=0.000000E+000
|RECORD=2|OwnerIndex=225|OwnerPartId=1|FormalType=1|Electrical=4|PinConglomerate=33|PinLength=10|Location.X=530|Location.Y=530|Name=1|Designator=1|SwapIdPin=1|SwapIDPart=1|PinPropagationDelay=0.000000E+000
|RECORD=13|OwnerIndex=225|IsNotAccesible=T|IndexInSheet=20|OwnerPartId=1|Location.X=530|Location.Y=522|Location.Y_Frac=50000|Corner.X=530|Corner.Y=520|LineWidth=1|Color=16711680
|RECORD=13|OwnerIndex=225|IsNotAccesible=T|IndexInSheet=21|OwnerPartId=1|Location.X=530|Location.Y=530|Corner.X=530|Corner.Y=527|Corner.Y_Frac=50000|LineWidth=1|Color=16711680
|RECORD=13|OwnerIndex=225|IsNotAccesible=T|IndexInSheet=22|OwnerPartId=1|Location.X=535|Location.Y=522|Location.Y_Frac=50000|Corner.X=525|Corner.Y=522|Corner.Y_Frac=50000|LineWidth=1|Color=16711680
|RECORD=13|OwnerIndex=225|IsNotAccesible=T|IndexInSheet=23|OwnerPartId=1|Location.X=535|Location.Y=527|Location.Y_Frac=50000|Corner.X=525|Corner.Y=527|Corner.Y_Frac=50000|LineWidth=1|Color=16711680
|RECORD=41|OwnerIndex=225|IndexInSheet=24|OwnerPartId=-1|Location.X=516|Location.Y=563|Location.Y_Frac=98951|Color=8388608|FontID=1|IsHidden=T|Text=<VALENTIUM>|Name=VALENTIUM PART NUM
|RECORD=34|OwnerIndex=225|IndexInSheet=-1|OwnerPartId=-1|Location.X=540|Location.Y=530|Color=8388608|FontID=5|Text=C5|Name=Designator|ReadOnlyState=1
|RECORD=41|OwnerIndex=225|IndexInSheet=-1|OwnerPartId=-1|Location.X=537|Location.X_Frac=50000|Location.Y=485|Color=8388608|FontID=2|IsHidden=T|Text=CAP_0805_10UF_25V|Name=Comment
|RECORD=44|OwnerIndex=225
|RECORD=45|OwnerIndex=255|IndexInSheet=-1|Description=Chip Capacitor, 0805, 2-Leads, Body 2.00x1.25mm, IPC Medium Density|UseComponentLibrary=T|ModelName=CAPC2012X14N|ModelType=PCBLIB|DatafileCount=1|ModelDatafileEntity0=CAPC2012X14N|ModelDatafileKind0=PCBLib|IsCurrent=T|DatalinksLocked=T|DatabaseDatalinksLocked=T|IntegratedModel=T|DatabaseModel=T
|RECORD=46|OwnerIndex=256
|RECORD=48|OwnerIndex=256
|RECORD=1|LibReference=CAP_0805_10UF_25V|ComponentDescription=CAP, CER, 10.UF, 25V, 10%, X5R, 0805|PartCount=2|DisplayModeCount=1|IndexInSheet=48|OwnerPartId=-1|Location.X=950|Location.Y=360|CurrentPartId=1|LibraryPath=*|SourceLibraryName=Capacitors.IntLib|TargetFileName=*|AreaColor=11599871|Color=128|PartIDLocked=F|DesignItemId=CAP_0805_10UF_25V|AllPinCount=2
|RECORD=41|OwnerIndex=259|OwnerPartId=-1|Location.X=950|Location.Y=360|Color=8388608|FontID=2|IsHidden=T|Text=TAIYO YUDEN|Name=MFG NAME
|RECORD=41|OwnerIndex=259|IndexInSheet=1|OwnerPartId=-1|Location.X=950|Location.Y=360|Color=8388608|FontID=2|IsHidden=T|Text=TMK212BBJ106KG-T|Name=MFG PART NUM
|RECORD=41|OwnerIndex=259|IndexInSheet=2|OwnerPartId=-1|Location.X=950|Location.Y=360|Color=8388608|FontID=2|IsHidden=T|Text=10/23/2013|Name=MODIFY DATE
|RECORD=41|OwnerIndex=259|IndexInSheet=3|OwnerPartId=-1|Location.X=950|Location.Y=360|Color=8388608|FontID=2|IsHidden=T|Text=CAP, CER|Name=CATEGORY
|RECORD=41|OwnerIndex=259|IndexInSheet=4|OwnerPartId=-1|Location.X=948|Location.Y=372|Location.Y_Frac=50000|Color=8388608|FontID=2|IsHidden=T|Text=4/11/2006 3:37:28 PM|Name=Date
|RECORD=41|OwnerIndex=259|IndexInSheet=5|OwnerPartId=-1|Location.X=956|Location.Y=434|Location.Y_Frac=48252|Color=8388608|FontID=2|IsHidden=T|Text=*|Name=SHEETPART
|RECORD=41|OwnerIndex=259|IndexInSheet=6|OwnerPartId=-1|Location.X=956|Location.Y=434|Location.Y_Frac=48252|Color=8388608|FontID=2|IsHidden=T|Text=10%|Name=P1
|RECORD=41|OwnerIndex=259|IndexInSheet=7|OwnerPartId=-1|Location.X=956|Location.Y=434|Location.Y_Frac=48252|Color=8388608|FontID=2|IsHidden=T|Text=85C|Name=MAXTEMP
|RECORD=41|OwnerIndex=259|IndexInSheet=8|OwnerPartId=-1|Location.X=956|Location.Y=434|Location.Y_Frac=48252|Color=8388608|FontID=2|IsHidden=T|Text=-55C|Name=MINTEMP
|RECORD=41|OwnerIndex=259|IndexInSheet=9|OwnerPartId=-1|Location.X=956|Location.Y=434|Location.Y_Frac=48252|Color=8388608|FontID=2|IsHidden=T|Name=OTHER
|RECORD=41|OwnerIndex=259|IndexInSheet=10|OwnerPartId=-1|Location.X=956|Location.Y=434|Location.Y_Frac=48252|Color=8388608|FontID=2|IsHidden=T|Text=25V|Name=P2
|RECORD=41|OwnerIndex=259|IndexInSheet=11|OwnerPartId=-1|Location.X=956|Location.Y=434|Location.Y_Frac=48252|Color=8388608|FontID=2|IsHidden=T|Text=X5R|Name=P3
|RECORD=41|OwnerIndex=259|IndexInSheet=12|OwnerPartId=-1|Location.X=956|Location.Y=434|Location.Y_Frac=48252|Color=8388608|FontID=2|IsHidden=T|Text=0805|Name=Size
|RECORD=41|OwnerIndex=259|IndexInSheet=13|OwnerPartId=-1|Location.X=956|Location.Y=434|Location.Y_Frac=48252|Color=8388608|FontID=2|IsHidden=T|Name=SUB
|RECORD=41|OwnerIndex=259|IndexInSheet=14|OwnerPartId=-1|Location.X=956|Location.Y=434|Location.Y_Frac=48252|Color=8388608|FontID=1|IsHidden=T|Text=CAP, CER, 10.UF, 10V, 10%, X5R, 0805|Name=DESC
|RECORD=41|OwnerIndex=259|IndexInSheet=15|OwnerPartId=-1|Location.X=956|Location.Y=433|Location.Y_Frac=98252|Color=8388608|FontID=1|IsHidden=T|Text=MOUSER|Name=Supplier 1|ReadOnlyState=1
|RECORD=41|OwnerIndex=259|IndexInSheet=16|OwnerPartId=-1|Location.X=956|Location.Y=433|Location.Y_Frac=98252|Color=8388608|FontID=1|IsHidden=T|Text=963-TMK212BBJ106KG-T|Name=Supplier Part Number 1|ReadOnlyState=1
|RECORD=41|OwnerIndex=259|IndexInSheet=17|OwnerPartId=-1|Location.X=980|Location.Y=390|Color=8388608|FontID=2|Text=10uF|Name=VALUE
|RECORD=2|OwnerIndex=259|OwnerPartId=1|FormalType=1|Electrical=4|PinConglomerate=35|PinLength=10|Location.X=970|Location.Y=390|Name=2|Designator=2|SwapIdPin=2|SwapIDPart=1|PinPropagationDelay=0.000000E+000
|RECORD=2|OwnerIndex=259|OwnerPartId=1|FormalType=1|Electrical=4|PinConglomerate=33|PinLength=10|Location.X=970|Location.Y=400|Name=1|Designator=1|SwapIdPin=1|SwapIDPart=1|PinPropagationDelay=0.000000E+000
|RECORD=13|OwnerIndex=259|IsNotAccesible=T|IndexInSheet=20|OwnerPartId=1|Location.X=970|Location.Y=392|Location.Y_Frac=50000|Corner.X=970|Corner.Y=390|LineWidth=1|Color=16711680
|RECORD=13|OwnerIndex=259|IsNotAccesible=T|IndexInSheet=21|OwnerPartId=1|Location.X=970|Location.Y=400|Corner.X=970|Corner.Y=397|Corner.Y_Frac=50000|LineWidth=1|Color=16711680
|RECORD=13|OwnerIndex=259|IsNotAccesible=T|IndexInSheet=22|OwnerPartId=1|Location.X=975|Location.Y=392|Location.Y_Frac=50000|Corner.X=965|Corner.Y=392|Corner.Y_Frac=50000|LineWidth=1|Color=16711680
|RECORD=13|OwnerIndex=259|IsNotAccesible=T|IndexInSheet=23|OwnerPartId=1|Location.X=975|Location.Y=397|Location.Y_Frac=50000|Corner.X=965|Corner.Y=397|Corner.Y_Frac=50000|LineWidth=1|Color=16711680
|RECORD=41|OwnerIndex=259|IndexInSheet=24|OwnerPartId=-1|Location.X=956|Location.Y=433|Location.Y_Frac=98951|Color=8388608|FontID=1|IsHidden=T|Text=<VALENTIUM>|Name=VALENTIUM PART NUM
|RECORD=34|OwnerIndex=259|IndexInSheet=-1|OwnerPartId=-1|Location.X=980|Location.Y=400|Color=8388608|FontID=5|Text=C7|Name=Designator|ReadOnlyState=1
|RECORD=41|OwnerIndex=259|IndexInSheet=-1|OwnerPartId=-1|Location.X=977|Location.X_Frac=50000|Location.Y=355|Color=8388608|FontID=2|IsHidden=T|Text=CAP_0805_10UF_25V|Name=Comment
|RECORD=44|OwnerIndex=259
|RECORD=45|OwnerIndex=289|IndexInSheet=-1|Description=Chip Capacitor, 0805, 2-Leads, Body 2.00x1.25mm, IPC Medium Density|UseComponentLibrary=T|ModelName=CAPC2012X14N|ModelType=PCBLIB|DatafileCount=1|ModelDatafileEntity0=CAPC2012X14N|ModelDatafileKind0=PCBLib|IsCurrent=T|DatalinksLocked=T|DatabaseDatalinksLocked=T|IntegratedModel=T|DatabaseModel=T
|RECORD=46|OwnerIndex=290
|RECORD=48|OwnerIndex=290
|RECORD=1|LibReference=CAP_0805_10UF_25V|ComponentDescription=CAP, CER, 10.UF, 25V, 10%, X5R, 0805|PartCount=2|DisplayModeCount=1|IndexInSheet=49|OwnerPartId=-1|Location.X=1000|Location.Y=360|CurrentPartId=1|LibraryPath=*|SourceLibraryName=Capacitors.IntLib|TargetFileName=*|AreaColor=11599871|Color=128|PartIDLocked=F|DesignItemId=CAP_0805_10UF_25V|AllPinCount=2
|RECORD=41|OwnerIndex=293|OwnerPartId=-1|Location.X=1000|Location.Y=360|Color=8388608|FontID=2|IsHidden=T|Text=TAIYO YUDEN|Name=MFG NAME
|RECORD=41|OwnerIndex=293|IndexInSheet=1|OwnerPartId=-1|Location.X=1000|Location.Y=360|Color=8388608|FontID=2|IsHidden=T|Text=TMK212BBJ106KG-T|Name=MFG PART NUM
|RECORD=41|OwnerIndex=293|IndexInSheet=2|OwnerPartId=-1|Location.X=1000|Location.Y=360|Color=8388608|FontID=2|IsHidden=T|Text=10/23/2013|Name=MODIFY DATE
|RECORD=41|OwnerIndex=293|IndexInSheet=3|OwnerPartId=-1|Location.X=1000|Location.Y=360|Color=8388608|FontID=2|IsHidden=T|Text=CAP, CER|Name=CATEGORY
|RECORD=41|OwnerIndex=293|IndexInSheet=4|OwnerPartId=-1|Location.X=998|Location.Y=372|Location.Y_Frac=50000|Color=8388608|FontID=2|IsHidden=T|Text=4/11/2006 3:37:28 PM|Name=Date
|RECORD=41|OwnerIndex=293|IndexInSheet=5|OwnerPartId=-1|Location.X=1006|Location.Y=434|Location.Y_Frac=48252|Color=8388608|FontID=2|IsHidden=T|Text=*|Name=SHEETPART
|RECORD=41|OwnerIndex=293|IndexInSheet=6|OwnerPartId=-1|Location.X=1006|Location.Y=434|Location.Y_Frac=48252|Color=8388608|FontID=2|IsHidden=T|Text=10%|Name=P1
|RECORD=41|OwnerIndex=293|IndexInSheet=7|OwnerPartId=-1|Location.X=1006|Location.Y=434|Location.Y_Frac=48252|Color=8388608|FontID=2|IsHidden=T|Text=85C|Name=MAXTEMP
|RECORD=41|OwnerIndex=293|IndexInSheet=8|OwnerPartId=-1|Location.X=1006|Location.Y=434|Location.Y_Frac=48252|Color=8388608|FontID=2|IsHidden=T|Text=-55C|Name=MINTEMP
|RECORD=41|OwnerIndex=293|IndexInSheet=9|OwnerPartId=-1|Location.X=1006|Location.Y=434|Location.Y_Frac=48252|Color=8388608|FontID=2|IsHidden=T|Name=OTHER
|RECORD=41|OwnerIndex=293|IndexInSheet=10|OwnerPartId=-1|Location.X=1006|Location.Y=434|Location.Y_Frac=48252|Color=8388608|FontID=2|IsHidden=T|Text=25V|Name=P2
|RECORD=41|OwnerIndex=293|IndexInSheet=11|OwnerPartId=-1|Location.X=1006|Location.Y=434|Location.Y_Frac=48252|Color=8388608|FontID=2|IsHidden=T|Text=X5R|Name=P3
|RECORD=41|OwnerIndex=293|IndexInSheet=12|OwnerPartId=-1|Location.X=1006|Location.Y=434|Location.Y_Frac=48252|Color=8388608|FontID=2|IsHidden=T|Text=0805|Name=Size
|RECORD=41|OwnerIndex=293|IndexInSheet=13|OwnerPartId=-1|Location.X=1006|Location.Y=434|Location.Y_Frac=48252|Color=8388608|FontID=2|IsHidden=T|Name=SUB
|RECORD=41|OwnerIndex=293|IndexInSheet=14|OwnerPartId=-1|Location.X=1006|Location.Y=434|Location.Y_Frac=48252|Color=8388608|FontID=1|IsHidden=T|Text=CAP, CER, 10.UF, 10V, 10%, X5R, 0805|Name=DESC
|RECORD=41|OwnerIndex=293|IndexInSheet=15|OwnerPartId=-1|Location.X=1006|Location.Y=433|Location.Y_Frac=98252|Color=8388608|FontID=1|IsHidden=T|Text=MOUSER|Name=Supplier 1|ReadOnlyState=1
|RECORD=41|OwnerIndex=293|IndexInSheet=16|OwnerPartId=-1|Location.X=1006|Location.Y=433|Location.Y_Frac=98252|Color=8388608|FontID=1|IsHidden=T|Text=963-TMK212BBJ106KG-T|Name=Supplier Part Number 1|ReadOnlyState=1
|RECORD=41|OwnerIndex=293|IndexInSheet=17|OwnerPartId=-1|Location.X=1030|Location.Y=390|Color=8388608|FontID=2|Text=10uF|Name=VALUE
|RECORD=2|OwnerIndex=293|OwnerPartId=1|FormalType=1|Electrical=4|PinConglomerate=35|PinLength=10|Location.X=1020|Location.Y=390|Name=2|Designator=2|SwapIdPin=2|SwapIDPart=1|PinPropagationDelay=0.000000E+000
|RECORD=2|OwnerIndex=293|OwnerPartId=1|FormalType=1|Electrical=4|PinConglomerate=33|PinLength=10|Location.X=1020|Location.Y=400|Name=1|Designator=1|SwapIdPin=1|SwapIDPart=1|PinPropagationDelay=0.000000E+000
|RECORD=13|OwnerIndex=293|IsNotAccesible=T|IndexInSheet=20|OwnerPartId=1|Location.X=1020|Location.Y=392|Location.Y_Frac=50000|Corner.X=1020|Corner.Y=390|LineWidth=1|Color=16711680
|RECORD=13|OwnerIndex=293|IsNotAccesible=T|IndexInSheet=21|OwnerPartId=1|Location.X=1020|Location.Y=400|Corner.X=1020|Corner.Y=397|Corner.Y_Frac=50000|LineWidth=1|Color=16711680
|RECORD=13|OwnerIndex=293|IsNotAccesible=T|IndexInSheet=22|OwnerPartId=1|Location.X=1025|Location.Y=392|Location.Y_Frac=50000|Corner.X=1015|Corner.Y=392|Corner.Y_Frac=50000|LineWidth=1|Color=16711680
|RECORD=13|OwnerIndex=293|IsNotAccesible=T|IndexInSheet=23|OwnerPartId=1|Location.X=1025|Location.Y=397|Location.Y_Frac=50000|Corner.X=1015|Corner.Y=397|Corner.Y_Frac=50000|LineWidth=1|Color=16711680
|RECORD=41|OwnerIndex=293|IndexInSheet=24|OwnerPartId=-1|Location.X=1006|Location.Y=433|Location.Y_Frac=98951|Color=8388608|FontID=1|IsHidden=T|Text=<VALENTIUM>|Name=VALENTIUM PART NUM
|RECORD=34|OwnerIndex=293|IndexInSheet=-1|OwnerPartId=-1|Location.X=1030|Location.Y=400|Color=8388608|FontID=5|Text=C8|Name=Designator|ReadOnlyState=1
|RECORD=41|OwnerIndex=293|IndexInSheet=-1|OwnerPartId=-1|Location.X=1027|Location.X_Frac=50000|Location.Y=355|Color=8388608|FontID=2|IsHidden=T|Text=CAP_0805_10UF_25V|Name=Comment
|RECORD=44|OwnerIndex=293
|RECORD=45|OwnerIndex=323|IndexInSheet=-1|Description=Chip Capacitor, 0805, 2-Leads, Body 2.00x1.25mm, IPC Medium Density|UseComponentLibrary=T|ModelName=CAPC2012X14N|ModelType=PCBLIB|DatafileCount=1|ModelDatafileEntity0=CAPC2012X14N|ModelDatafileKind0=PCBLib|IsCurrent=T|DatalinksLocked=T|DatabaseDatalinksLocked=T|IntegratedModel=T|DatabaseModel=T
|RECORD=46|OwnerIndex=324
|RECORD=48|OwnerIndex=324
|RECORD=1|LibReference=SMTLED_RED_0603_SML|ComponentDescription=LED, RED, SML-LX0603, 635NM, 2V, 20MA, 0603|PartCount=2|DisplayModeCount=1|IndexInSheet=50|OwnerPartId=-1|Location.X=1330|Location.Y=430|Orientation=3|CurrentPartId=1|LibraryPath=*|SourceLibraryName=Passives.IntLib|TargetFileName=*|AreaColor=11599871|Color=128|PartIDLocked=F|DesignItemId=SMTLED_RED_0603_SML|AllPinCount=2
|RECORD=41|OwnerIndex=327|OwnerPartId=-1|Location.X=1317|Location.X_Frac=50000|Location.Y=432|Color=8388608|FontID=2|IsHidden=T|Text=SML-LX0603IW-TR|Name=MFG PART NUM
|RECORD=41|OwnerIndex=327|IndexInSheet=1|OwnerPartId=-1|Location.X=1317|Location.X_Frac=50000|Location.Y=432|Color=8388608|FontID=2|IsHidden=T|Text=9/4/2013|Name=MODIFY DATE
|RECORD=41|OwnerIndex=327|IndexInSheet=2|OwnerPartId=-1|Location.X=1317|Location.X_Frac=50000|Location.Y=432|Color=8388608|FontID=2|IsHidden=T|Text=LUMEX|Name=MFG NAME
|RECORD=41|OwnerIndex=327|IndexInSheet=3|OwnerPartId=-1|Location.X=1317|Location.X_Frac=50000|Location.Y=432|Color=8388608|FontID=2|IsHidden=T|Text=LED|Name=CATEGORY
|RECORD=41|OwnerIndex=327|IndexInSheet=4|OwnerPartId=-1|Location.X=1317|Location.X_Frac=50000|Location.Y=432|Color=8388608|FontID=2|IsHidden=T|Name=Date
|RECORD=41|OwnerIndex=327|IndexInSheet=5|OwnerPartId=-1|Location.X=1317|Location.X_Frac=50000|Location.Y=432|Color=8388608|FontID=2|IsHidden=T|Text=85C|Name=MAXTEMP
|RECORD=41|OwnerIndex=327|IndexInSheet=6|OwnerPartId=-1|Location.X=1317|Location.X_Frac=50000|Location.Y=432|Color=8388608|FontID=2|IsHidden=T|Text=-25C|Name=MINTEMP
|RECORD=41|OwnerIndex=327|IndexInSheet=7|OwnerPartId=-1|Location.X=1317|Location.X_Frac=50000|Location.Y=432|Color=8388608|FontID=2|IsHidden=T|Text=SML-LX0603|Name=OTHER
|RECORD=41|OwnerIndex=327|IndexInSheet=8|OwnerPartId=-1|Location.X=1317|Location.X_Frac=50000|Location.Y=432|Color=8388608|FontID=2|IsHidden=T|Text=635NM|Name=P1
|RECORD=41|OwnerIndex=327|IndexInSheet=9|OwnerPartId=-1|Location.X=1317|Location.X_Frac=50000|Location.Y=432|Color=8388608|FontID=2|IsHidden=T|Text=2V|Name=P2
|RECORD=41|OwnerIndex=327|IndexInSheet=10|OwnerPartId=-1|Location.X=1317|Location.X_Frac=50000|Location.Y=432|Color=8388608|FontID=2|IsHidden=T|Text=20MA|Name=P3
|RECORD=41|OwnerIndex=327|IndexInSheet=11|OwnerPartId=-1|Location.X=1317|Location.X_Frac=50000|Location.Y=432|Color=8388608|FontID=2|IsHidden=T|Name=SUB
|RECORD=41|OwnerIndex=327|IndexInSheet=12|OwnerPartId=-1|Location.X=1317|Location.X_Frac=50000|Location.Y=432|Color=8388608|FontID=2|IsHidden=T|Text=0603|Name=SIZE
|RECORD=41|OwnerIndex=327|IndexInSheet=13|OwnerPartId=-1|Location.X=1317|Location.X_Frac=50000|Location.Y=432|Color=8388608|FontID=1|IsHidden=T|Text=*|Name=SHEETPART
|RECORD=41|OwnerIndex=327|IndexInSheet=14|OwnerPartId=-1|Location.X=1317|Location.X_Frac=50000|Location.Y=432|Color=8388608|FontID=1|IsHidden=T|Text=LED, RED, SML-LX0603, 635NM, 2V, 20MA, 0603|Name=DESC
|RECORD=41|OwnerIndex=327|IndexInSheet=15|OwnerPartId=-1|Location.X=1317|Location.X_Frac=50000|Location.Y=432|Color=8388608|FontID=1|IsHidden=T|Text=Digi-Key|Name=Supplier 1|ReadOnlyState=3
|RECORD=41|OwnerIndex=327|IndexInSheet=16|OwnerPartId=-1|Location.X=1317|Location.X_Frac=50000|Location.Y=432|Color=8388608|FontID=1|IsHidden=T|Text=67-1548-1-ND|Name=Supplier Part Number 1|ReadOnlyState=3
|RECORD=41|OwnerIndex=327|IndexInSheet=17|OwnerPartId=-1|Location.X=1350|Location.Y=386|Location.Y_Frac=50000|Color=8388608|FontID=2|Text=RED|Name=VALUE
|RECORD=2|OwnerIndex=327|OwnerPartId=1|FormalType=1|Electrical=4|PinConglomerate=33|PinLength=20|Location.X=1330|Location.Y=410|Name=A|Designator=2|PinPropagationDelay=0.000000E+000
|RECORD=2|OwnerIndex=327|OwnerPartId=1|FormalType=1|Electrical=4|PinConglomerate=35|PinLength=20|Location.X=1330|Location.Y=390|Name=K|Designator=1|PinPropagationDelay=0.000000E+000
|RECORD=12|OwnerIndex=327|IsNotAccesible=T|IndexInSheet=20|OwnerPartId=1|Location.X=1330|Location.Y=400|Radius=12|Radius_Frac=50000|LineWidth=1|EndAngle=360.000|Color=16711680
|RECORD=13|OwnerIndex=327|IsNotAccesible=T|IndexInSheet=21|OwnerPartId=1|Location.X=1338|Location.Y=394|Corner.X=1323|Corner.Y=394|LineWidth=1|Color=16711680
|RECORD=13|OwnerIndex=327|IsNotAccesible=T|IndexInSheet=22|OwnerPartId=1|Location.X=1345|Location.Y=381|Corner.X=1338|Corner.X_Frac=70000|Corner.Y=387|Corner.Y_Frac=20000|LineWidth=1|Color=16711680
|RECORD=13|OwnerIndex=327|IsNotAccesible=T|IndexInSheet=23|OwnerPartId=1|Location.X=1349|Location.Y=385|Corner.X=1342|Corner.X_Frac=80000|Corner.Y=391|Corner.Y_Frac=30000|LineWidth=1|Color=16711680
|RECORD=13|OwnerIndex=327|IsNotAccesible=T|IndexInSheet=24|OwnerPartId=1|Location.X=1330|Location.Y=390|Corner.X=1330|Corner.Y=393|Corner.Y_Frac=80000|LineWidth=1|Color=16711680
|RECORD=13|OwnerIndex=327|IsNotAccesible=T|IndexInSheet=25|OwnerPartId=1|Location.X=1330|Location.Y=406|Corner.X=1330|Corner.Y=409|Corner.Y_Frac=70000|LineWidth=1|Color=16711680
|RECORD=7|OwnerIndex=327|IsNotAccesible=T|IndexInSheet=26|OwnerPartId=1|LineWidth=1|Color=16711680|AreaColor=16711680|IsSolid=T|LocationCount=3|X1=1344|Y1=384|X2=1342|Y2=382|X3=1345|Y3=381
|RECORD=7|OwnerIndex=327|IsNotAccesible=T|IndexInSheet=27|OwnerPartId=1|LineWidth=1|Color=16711680|AreaColor=16711680|IsSolid=T|LocationCount=3|X1=1348|Y1=388|X2=1346|Y2=386|X3=1349|Y3=385
|RECORD=7|OwnerIndex=327|IsNotAccesible=T|IndexInSheet=28|OwnerPartId=1|LineWidth=1|Color=16711680|AreaColor=16777215|IsSolid=T|LocationCount=3|X1=1330|Y1=394|X2=1338|Y2=406|X3=1322|Y3=406
|RECORD=41|OwnerIndex=327|IndexInSheet=29|OwnerPartId=-1|Location.X=1317|Location.X_Frac=50000|Location.Y=432|Color=8388608|FontID=1|IsHidden=T|Text=<VALENTIUM>|Name=VALENTIUM PART NUM
|RECORD=34|OwnerIndex=327|IndexInSheet=-1|OwnerPartId=-1|Location.X=1350|Location.Y=398|Location.Y_Frac=50000|Color=8388608|FontID=5|Text=D4|Name=Designator|ReadOnlyState=1
|RECORD=41|OwnerIndex=327|IndexInSheet=-1|OwnerPartId=-1|Location.X=1317|Location.X_Frac=50000|Location.Y=432|Color=8388608|FontID=2|IsHidden=T|Text==VALUE|Name=Comment|ReadOnlyState=1
|RECORD=44|OwnerIndex=327
|RECORD=45|OwnerIndex=362|IndexInSheet=-1|Description=Molded Diode, 0603, 2-Leads, Body 1.60x0.80mm, IPC Medium Density|UseComponentLibrary=T|ModelName=DIOM1608X06N|ModelType=PCBLIB|DatafileCount=1|ModelDatafileEntity0=DIOM1608X06N|ModelDatafileKind0=PCBLib|IsCurrent=T|DatalinksLocked=T|DatabaseDatalinksLocked=T|IntegratedModel=T|DatabaseModel=T
|RECORD=46|OwnerIndex=363
|RECORD=48|OwnerIndex=363
|RECORD=1|LibReference=RES_0603_200|ComponentDescription=RES, 200 OHM, 1%, 1/10W, TF, 0603|PartCount=2|DisplayModeCount=1|IndexInSheet=51|OwnerPartId=-1|Location.X=1330|Location.Y=300|Orientation=1|CurrentPartId=1|LibraryPath=*|SourceLibraryName=Resistors.IntLib|TargetFileName=*|AreaColor=11599871|Color=128|PartIDLocked=F|DesignItemId=RES_0603_200|AllPinCount=2
|RECORD=41|OwnerIndex=366|OwnerPartId=-1|Location.X=1326|Location.Y=352|Color=8388608|FontID=2|IsHidden=T|Text=7/25/2013|Name=ModifyDate
|RECORD=41|OwnerIndex=366|IndexInSheet=1|OwnerPartId=-1|Location.X=1326|Location.Y=352|Color=8388608|FontID=2|IsHidden=T|Text=ERJ-3EKF2000V|Name=MFG PART NUM
|RECORD=41|OwnerIndex=366|IndexInSheet=2|OwnerPartId=-1|Location.X=1326|Location.Y=352|Color=8388608|FontID=2|IsHidden=T|Text=PANASONIC|Name=MFG NAME
|RECORD=41|OwnerIndex=366|IndexInSheet=3|OwnerPartId=-1|Location.X=1326|Location.Y=352|Color=8388608|FontID=2|IsHidden=T|Text=RES|Name=CATEGORY
|RECORD=41|OwnerIndex=366|IndexInSheet=4|OwnerPartId=-1|Location.X=1326|Location.Y=352|Color=8388608|FontID=2|IsHidden=T|Text=7/26/2013|Name=Date
|RECORD=41|OwnerIndex=366|IndexInSheet=5|OwnerPartId=-1|Location.X=1326|Location.Y=352|Color=8388608|FontID=2|IsHidden=T|Text=1%|Name=P1
|RECORD=41|OwnerIndex=366|IndexInSheet=6|OwnerPartId=-1|Location.X=1326|Location.Y=352|Color=8388608|FontID=2|IsHidden=T|Text=TF|Name=P3
|RECORD=41|OwnerIndex=366|IndexInSheet=7|OwnerPartId=-1|Location.X=1326|Location.Y=352|Color=8388608|FontID=2|IsHidden=T|Text=1/10W|Name=P2
|RECORD=41|OwnerIndex=366|IndexInSheet=8|OwnerPartId=-1|Location.X=1326|Location.Y=352|Color=8388608|FontID=2|IsHidden=T|Text=125C|Name=MAXTEMP
|RECORD=41|OwnerIndex=366|IndexInSheet=9|OwnerPartId=-1|Location.X=1326|Location.Y=352|Color=8388608|FontID=2|IsHidden=T|Text=-55C|Name=MINTEMP
|RECORD=41|OwnerIndex=366|IndexInSheet=10|OwnerPartId=-1|Location.X=1326|Location.Y=352|Color=8388608|FontID=2|IsHidden=T|Text=100PPM|Name=OTHER
|RECORD=41|OwnerIndex=366|IndexInSheet=11|OwnerPartId=-1|Location.X=1326|Location.Y=352|Color=8388608|FontID=2|IsHidden=T|Text=0603|Name=SIZE
|RECORD=41|OwnerIndex=366|IndexInSheet=12|OwnerPartId=-1|Location.X=1326|Location.Y=352|Color=8388608|FontID=2|IsHidden=T|Text=GENERIC|Name=SUB
|RECORD=41|OwnerIndex=366|IndexInSheet=13|OwnerPartId=-1|Location.X=1326|Location.Y=352|Color=8388608|FontID=1|IsHidden=T|Text=*|Name=SHEETPART
|RECORD=41|OwnerIndex=366|IndexInSheet=14|OwnerPartId=-1|Location.X=1326|Location.Y=352|Color=8388608|FontID=1|IsHidden=T|Text=RES, 200 OHM, 1%, 1/10W, TF, 0603|Name=DESC
|RECORD=41|OwnerIndex=366|IndexInSheet=15|OwnerPartId=-1|Location.X=1326|Location.Y=352|Color=8388608|FontID=1|IsHidden=T|Text=Digi-Key|Name=Supplier 1|ReadOnlyState=3
|RECORD=41|OwnerIndex=366|IndexInSheet=16|OwnerPartId=-1|Location.X=1326|Location.Y=352|Color=8388608|FontID=1|IsHidden=T|Text=P200HCT-ND|Name=Supplier Part Number 1|ReadOnlyState=3
|RECORD=41|OwnerIndex=366|IndexInSheet=17|OwnerPartId=-1|Location.X=1326|Location.Y=352|Color=8388608|FontID=1|IsHidden=T|Text=<VELENTIUM>|Name=VELENTIUM PART NUM
|RECORD=41|OwnerIndex=366|IndexInSheet=18|OwnerPartId=-1|Location.X=1334|Location.Y=315|Color=8388608|FontID=2|Text=200 OHM|Name=VALUE
|RECORD=2|OwnerIndex=366|OwnerPartId=1|FormalType=1|Electrical=4|PinConglomerate=35|PinLength=10|Location.X=1330|Location.Y=310|Name=1|Designator=1|PinPropagationDelay=0.000000E+000
|RECORD=2|OwnerIndex=366|OwnerPartId=1|FormalType=1|Electrical=4|PinConglomerate=33|PinLength=10|Location.X=1330|Location.Y=340|Name=2|Designator=2|PinPropagationDelay=0.000000E+000
|RECORD=6|OwnerIndex=366|IsNotAccesible=T|IndexInSheet=21|OwnerPartId=1|LineWidth=1|Color=16711680|LocationCount=7|X1=1330|Y1=340|X2=1327|Y2=337|X3=1333|Y3=331|X4=1327|Y4=325|X5=1333|Y5=319|X6=1327|Y6=313|X7=1330|Y7=310
|RECORD=34|OwnerIndex=366|IndexInSheet=-1|OwnerPartId=-1|Location.X=1334|Location.Y=327|Color=8388608|FontID=5|Text=R1|Name=Designator|ReadOnlyState=1
|RECORD=41|OwnerIndex=366|IndexInSheet=-1|OwnerPartId=-1|Location.X=1326|Location.Y=352|Color=8388608|FontID=2|IsHidden=T|Text==MFG PART NUM|Name=Comment
|RECORD=44|OwnerIndex=366
|RECORD=45|OwnerIndex=393|IndexInSheet=-1|Description=Chip Resistor, 0603, 2-Leads, Body 1.57x0.85mm, IPC Medium Density|UseComponentLibrary=T|ModelName=RESC1608X50N|ModelType=PCBLIB|DatafileCount=1|ModelDatafileEntity0=RESC1608X50N|ModelDatafileKind0=PCBLib|IsCurrent=T|DatalinksLocked=T|DatabaseDatalinksLocked=T|IntegratedModel=T|DatabaseModel=T
|RECORD=46|OwnerIndex=394
|RECORD=48|OwnerIndex=394
|RECORD=1|LibReference=RES_0603_47K|ComponentDescription=RES, 47K, 1%, 1/10W, TF, 0603|PartCount=2|DisplayModeCount=1|IndexInSheet=52|OwnerPartId=-1|Location.X=590|Location.Y=900|Orientation=1|CurrentPartId=1|LibraryPath=*|SourceLibraryName=Resistors.IntLib|TargetFileName=*|AreaColor=11599871|Color=128|PartIDLocked=F|DesignItemId=RES_0603_47K|AllPinCount=2
|RECORD=41|OwnerIndex=397|OwnerPartId=-1|Location.X=586|Location.Y=952|Color=8388608|FontID=2|IsHidden=T|Text=1/22/2014|Name=ModifyDate
|RECORD=41|OwnerIndex=397|IndexInSheet=1|OwnerPartId=-1|Location.X=586|Location.Y=952|Color=8388608|FontID=2|IsHidden=T|Text=ERJ-3EKF4702V|Name=MFG PART NUM
|RECORD=41|OwnerIndex=397|IndexInSheet=2|OwnerPartId=-1|Location.X=586|Location.Y=952|Color=8388608|FontID=2|IsHidden=T|Text=PANASONIC|Name=MFG NAME
|RECORD=41|OwnerIndex=397|IndexInSheet=3|OwnerPartId=-1|Location.X=586|Location.Y=952|Color=8388608|FontID=2|IsHidden=T|Text=RES|Name=CATEGORY
|RECORD=41|OwnerIndex=397|IndexInSheet=4|OwnerPartId=-1|Location.X=586|Location.Y=952|Color=8388608|FontID=2|IsHidden=T|Text=1/22/2014|Name=Date
|RECORD=41|OwnerIndex=397|IndexInSheet=5|OwnerPartId=-1|Location.X=586|Location.Y=952|Color=8388608|FontID=2|IsHidden=T|Text=1%|Name=P1
|RECORD=41|OwnerIndex=397|IndexInSheet=6|OwnerPartId=-1|Location.X=586|Location.Y=952|Color=8388608|FontID=2|IsHidden=T|Text=TF|Name=P3
|RECORD=41|OwnerIndex=397|IndexInSheet=7|OwnerPartId=-1|Location.X=586|Location.Y=952|Color=8388608|FontID=2|IsHidden=T|Text=1/10W|Name=P2
|RECORD=41|OwnerIndex=397|IndexInSheet=8|OwnerPartId=-1|Location.X=586|Location.Y=952|Color=8388608|FontID=2|IsHidden=T|Text=125C|Name=MAXTEMP
|RECORD=41|OwnerIndex=397|IndexInSheet=9|OwnerPartId=-1|Location.X=586|Location.Y=952|Color=8388608|FontID=2|IsHidden=T|Text=-55C|Name=MINTEMP
|RECORD=41|OwnerIndex=397|IndexInSheet=10|OwnerPartId=-1|Location.X=586|Location.Y=952|Color=8388608|FontID=2|IsHidden=T|Text=100PPM|Name=OTHER
|RECORD=41|OwnerIndex=397|IndexInSheet=11|OwnerPartId=-1|Location.X=586|Location.Y=952|Color=8388608|FontID=2|IsHidden=T|Text=0603|Name=SIZE
|RECORD=41|OwnerIndex=397|IndexInSheet=12|OwnerPartId=-1|Location.X=586|Location.Y=952|Color=8388608|FontID=2|IsHidden=T|Text=GENERIC|Name=SUB
|RECORD=41|OwnerIndex=397|IndexInSheet=13|OwnerPartId=-1|Location.X=586|Location.Y=952|Color=8388608|FontID=1|IsHidden=T|Text=*|Name=SHEETPART
|RECORD=41|OwnerIndex=397|IndexInSheet=14|OwnerPartId=-1|Location.X=586|Location.Y=952|Color=8388608|FontID=1|IsHidden=T|Text=RES, 47K, 1%, 1/10W, TF, 0603|Name=DESC
|RECORD=41|OwnerIndex=397|IndexInSheet=15|OwnerPartId=-1|Location.X=586|Location.Y=952|Color=8388608|FontID=1|IsHidden=T|Text=Digi-Key|Name=Supplier 1|ReadOnlyState=3
|RECORD=41|OwnerIndex=397|IndexInSheet=16|OwnerPartId=-1|Location.X=586|Location.Y=952|Color=8388608|FontID=1|IsHidden=T|Text=P47.0KHCT-ND|Name=Supplier Part Number 1|ReadOnlyState=3
|RECORD=41|OwnerIndex=397|IndexInSheet=17|OwnerPartId=-1|Location.X=594|Location.Y=915|Color=8388608|FontID=2|Text=47K|Name=VALUE
|RECORD=2|OwnerIndex=397|OwnerPartId=1|FormalType=1|Electrical=4|PinConglomerate=35|PinLength=10|Location.X=590|Location.Y=910|Name=1|Designator=1|PinPropagationDelay=0.000000E+000
|RECORD=2|OwnerIndex=397|OwnerPartId=1|FormalType=1|Electrical=4|PinConglomerate=33|PinLength=10|Location.X=590|Location.Y=940|Name=2|Designator=2|PinPropagationDelay=0.000000E+000
|RECORD=6|OwnerIndex=397|IsNotAccesible=T|IndexInSheet=20|OwnerPartId=1|LineWidth=1|Color=16711680|LocationCount=7|X1=590|Y1=940|X2=587|Y2=937|X3=593|Y3=931|X4=587|Y4=925|X5=593|Y5=919|X6=587|Y6=913|X7=590|Y7=910
|RECORD=41|OwnerIndex=397|IndexInSheet=21|OwnerPartId=-1|Location.X=586|Location.Y=952|Color=8388608|FontID=1|IsHidden=T|Text=<VELENTIUM>|Name=VELENTIUM PART NUM
|RECORD=34|OwnerIndex=397|IndexInSheet=-1|OwnerPartId=-1|Location.X=594|Location.Y=927|Color=8388608|FontID=5|Text=R2|Name=Designator|ReadOnlyState=1
|RECORD=41|OwnerIndex=397|IndexInSheet=-1|OwnerPartId=-1|Location.X=586|Location.Y=952|Color=8388608|FontID=2|IsHidden=T|Text==MFG PART NUM|Name=Comment
|RECORD=44|OwnerIndex=397
|RECORD=45|OwnerIndex=424|IndexInSheet=-1|Description=Chip Resistor, 0603, 2-Leads, Body 1.57x0.85mm, IPC Medium Density|UseComponentLibrary=T|ModelName=RESC1608X50N|ModelType=PCBLIB|DatafileCount=1|ModelDatafileEntity0=RESC1608X50N|ModelDatafileKind0=PCBLib|IsCurrent=T|DatalinksLocked=T|DatabaseDatalinksLocked=T|IntegratedModel=T|DatabaseModel=T
|RECORD=46|OwnerIndex=425
|RECORD=48|OwnerIndex=425
|RECORD=1|LibReference=RES_0603_2.2K|ComponentDescription=RES, 2.2K, 1%, 1/10W, TF, 0603|PartCount=2|DisplayModeCount=1|IndexInSheet=53|OwnerPartId=-1|Location.X=690|Location.Y=730|CurrentPartId=1|LibraryPath=*|SourceLibraryName=Resistors.IntLib|TargetFileName=*|AreaColor=11599871|Color=128|PartIDLocked=F|DesignItemId=RES_0603_2.2K|AllPinCount=2
|RECORD=41|OwnerIndex=428|OwnerPartId=-1|Location.X=690|Location.Y=730|Color=8388608|FontID=2|IsHidden=T|Text=8/15/2013|Name=ModifyDate
|RECORD=41|OwnerIndex=428|IndexInSheet=1|OwnerPartId=-1|Location.X=690|Location.Y=730|Color=8388608|FontID=2|IsHidden=T|Text=ERJ-3EKF2201V|Name=MFG PART NUM
|RECORD=41|OwnerIndex=428|IndexInSheet=2|OwnerPartId=-1|Location.X=690|Location.Y=730|Color=8388608|FontID=2|IsHidden=T|Text=PANASONIC|Name=MFG NAME
|RECORD=41|OwnerIndex=428|IndexInSheet=3|OwnerPartId=-1|Location.X=690|Location.Y=730|Color=8388608|FontID=2|IsHidden=T|Text=RES|Name=CATEGORY
|RECORD=41|OwnerIndex=428|IndexInSheet=4|OwnerPartId=-1|Location.X=688|Location.Y=740|Color=8388608|FontID=2|IsHidden=T|Text=8/15/2013|Name=Date
|RECORD=41|OwnerIndex=428|IndexInSheet=5|OwnerPartId=-1|Location.X=680|Location.X_Frac=55769|Location.Y=740|Color=8388608|FontID=2|IsHidden=T|Text=1%|Name=P1
|RECORD=41|OwnerIndex=428|IndexInSheet=6|OwnerPartId=-1|Location.X=680|Location.X_Frac=55769|Location.Y=740|Color=8388608|FontID=2|IsHidden=T|Text=TF|Name=P3
|RECORD=41|OwnerIndex=428|IndexInSheet=7|OwnerPartId=-1|Location.X=680|Location.X_Frac=55769|Location.Y=740|Color=8388608|FontID=2|IsHidden=T|Text=1/10W|Name=P2
|RECORD=41|OwnerIndex=428|IndexInSheet=8|OwnerPartId=-1|Location.X=680|Location.X_Frac=55769|Location.Y=740|Color=8388608|FontID=2|IsHidden=T|Text=125C|Name=MAXTEMP
|RECORD=41|OwnerIndex=428|IndexInSheet=9|OwnerPartId=-1|Location.X=680|Location.X_Frac=55769|Location.Y=740|Color=8388608|FontID=2|IsHidden=T|Text=-55C|Name=MINTEMP
|RECORD=41|OwnerIndex=428|IndexInSheet=10|OwnerPartId=-1|Location.X=680|Location.X_Frac=55769|Location.Y=740|Color=8388608|FontID=2|IsHidden=T|Text=100PPM|Name=OTHER
|RECORD=41|OwnerIndex=428|IndexInSheet=11|OwnerPartId=-1|Location.X=680|Location.X_Frac=55769|Location.Y=740|Color=8388608|FontID=2|IsHidden=T|Text=0603|Name=SIZE
|RECORD=41|OwnerIndex=428|IndexInSheet=12|OwnerPartId=-1|Location.X=680|Location.X_Frac=55769|Location.Y=740|Color=8388608|FontID=2|IsHidden=T|Text=GENERIC|Name=SUB
|RECORD=41|OwnerIndex=428|IndexInSheet=13|OwnerPartId=-1|Location.X=675|Location.X_Frac=98077|Location.Y=744|Color=8388608|FontID=2|IsHidden=T|Text=Digi-Key|Name=Supplier 1|ReadOnlyState=3
|RECORD=41|OwnerIndex=428|IndexInSheet=14|OwnerPartId=-1|Location.X=675|Location.X_Frac=98077|Location.Y=744|Color=8388608|FontID=2|IsHidden=T|Text=P2.20KHCT-ND|Name=Supplier Part Number 1|ReadOnlyState=3
|RECORD=41|OwnerIndex=428|IndexInSheet=15|OwnerPartId=-1|Location.X=675|Location.X_Frac=98077|Location.Y=716|Color=8388608|FontID=1|IsHidden=T|Text=*|Name=SHEETPART
|RECORD=41|OwnerIndex=428|IndexInSheet=16|OwnerPartId=-1|Location.X=675|Location.X_Frac=98077|Location.Y=744|Color=8388608|FontID=1|IsHidden=T|Text=RES, 2.2K, 1%, 1/10W, TF, 0603|Name=DESC
|RECORD=41|OwnerIndex=428|IndexInSheet=17|OwnerPartId=-1|Location.X=699|Location.Y=714|Color=8388608|FontID=2|Text=2.2K|Name=VALUE
|RECORD=2|OwnerIndex=428|OwnerPartId=1|FormalType=1|Electrical=4|PinConglomerate=34|PinLength=10|Location.X=700|Location.Y=730|Name=1|Designator=1|PinPropagationDelay=0.000000E+000
|RECORD=2|OwnerIndex=428|OwnerPartId=1|FormalType=1|Electrical=4|PinConglomerate=32|PinLength=10|Location.X=730|Location.Y=730|Name=2|Designator=2|PinPropagationDelay=0.000000E+000
|RECORD=6|OwnerIndex=428|IsNotAccesible=T|IndexInSheet=20|OwnerPartId=1|LineWidth=1|Color=16711680|LocationCount=7|X1=730|Y1=730|X2=727|Y2=733|X3=721|Y3=727|X4=715|Y4=733|X5=709|Y5=727|X6=703|Y6=733|X7=700|Y7=730
|RECORD=41|OwnerIndex=428|IndexInSheet=21|OwnerPartId=-1|Location.X=676|Location.X_Frac=61102|Location.Y=744|Color=8388608|FontID=1|IsHidden=T|Text=<VELENTIUM>|Name=VELENTIUM PART NUM
|RECORD=34|OwnerIndex=428|IndexInSheet=-1|OwnerPartId=-1|Location.X=699|Location.Y=734|Color=8388608|FontID=5|Text=R8|Name=Designator|ReadOnlyState=1
|RECORD=41|OwnerIndex=428|IndexInSheet=-1|OwnerPartId=-1|Location.X=710|Location.Y=720|Color=8388608|FontID=2|IsHidden=T|Text==MFG PART NUM|Name=Comment
|RECORD=44|OwnerIndex=428
|RECORD=45|OwnerIndex=455|IndexInSheet=-1|Description=Chip Resistor, 0603, 2-Leads, Body 1.57x0.85mm, IPC Medium Density|UseComponentLibrary=T|ModelName=RESC1608X50N|ModelType=PCBLIB|DatafileCount=1|ModelDatafileEntity0=RESC1608X50N|ModelDatafileKind0=PCBLib|IsCurrent=T|DatalinksLocked=T|DatabaseDatalinksLocked=T|IntegratedModel=T|DatabaseModel=T
|RECORD=46|OwnerIndex=456
|RECORD=48|OwnerIndex=456
|RECORD=1|LibReference=RES_0603_10K|ComponentDescription=RES, 10K, 1%, 1/10W, TF, 0603|PartCount=2|DisplayModeCount=1|IndexInSheet=54|OwnerPartId=-1|Location.X=860|Location.Y=760|Orientation=1|CurrentPartId=1|LibraryPath=*|SourceLibraryName=Resistors.IntLib|TargetFileName=*|AreaColor=11599871|Color=128|PartIDLocked=F|DesignItemId=RES_0603_10K|AllPinCount=2
|RECORD=41|OwnerIndex=459|OwnerPartId=-1|Location.X=856|Location.Y=812|Color=8388608|FontID=2|IsHidden=T|Text=7/25/2013|Name=ModifyDate
|RECORD=41|OwnerIndex=459|IndexInSheet=1|OwnerPartId=-1|Location.X=856|Location.Y=812|Color=8388608|FontID=2|IsHidden=T|Text=ERJ-3EKF1002V|Name=MFG PART NUM
|RECORD=41|OwnerIndex=459|IndexInSheet=2|OwnerPartId=-1|Location.X=856|Location.Y=812|Color=8388608|FontID=2|IsHidden=T|Text=PANASONIC|Name=MFG NAME
|RECORD=41|OwnerIndex=459|IndexInSheet=3|OwnerPartId=-1|Location.X=856|Location.Y=812|Color=8388608|FontID=2|IsHidden=T|Text=RES|Name=CATEGORY
|RECORD=41|OwnerIndex=459|IndexInSheet=4|OwnerPartId=-1|Location.X=856|Location.Y=812|Color=8388608|FontID=2|IsHidden=T|Text=7/26/2013|Name=Date
|RECORD=41|OwnerIndex=459|IndexInSheet=5|OwnerPartId=-1|Location.X=856|Location.Y=812|Color=8388608|FontID=2|IsHidden=T|Text=1%|Name=P1
|RECORD=41|OwnerIndex=459|IndexInSheet=6|OwnerPartId=-1|Location.X=856|Location.Y=812|Color=8388608|FontID=2|IsHidden=T|Text=TF|Name=P3
|RECORD=41|OwnerIndex=459|IndexInSheet=7|OwnerPartId=-1|Location.X=856|Location.Y=812|Color=8388608|FontID=2|IsHidden=T|Text=1/10W|Name=P2
|RECORD=41|OwnerIndex=459|IndexInSheet=8|OwnerPartId=-1|Location.X=856|Location.Y=812|Color=8388608|FontID=2|IsHidden=T|Text=125C|Name=MAXTEMP
|RECORD=41|OwnerIndex=459|IndexInSheet=9|OwnerPartId=-1|Location.X=856|Location.Y=812|Color=8388608|FontID=2|IsHidden=T|Text=-55C|Name=MINTEMP
|RECORD=41|OwnerIndex=459|IndexInSheet=10|OwnerPartId=-1|Location.X=856|Location.Y=812|Color=8388608|FontID=2|IsHidden=T|Text=100PPM|Name=OTHER
|RECORD=41|OwnerIndex=459|IndexInSheet=11|OwnerPartId=-1|Location.X=856|Location.Y=812|Color=8388608|FontID=2|IsHidden=T|Text=0603|Name=SIZE
|RECORD=41|OwnerIndex=459|IndexInSheet=12|OwnerPartId=-1|Location.X=856|Location.Y=812|Color=8388608|FontID=2|IsHidden=T|Text=GENERIC|Name=SUB
|RECORD=41|OwnerIndex=459|IndexInSheet=13|OwnerPartId=-1|Location.X=856|Location.Y=812|Color=8388608|FontID=2|IsHidden=T|Text=Digi-Key|Name=Supplier 1|ReadOnlyState=3
|RECORD=41|OwnerIndex=459|IndexInSheet=14|OwnerPartId=-1|Location.X=856|Location.Y=812|Color=8388608|FontID=2|IsHidden=T|Text=P10.0KHCT-ND|Name=Supplier Part Number 1|ReadOnlyState=3
|RECORD=41|OwnerIndex=459|IndexInSheet=15|OwnerPartId=-1|Location.X=856|Location.Y=812|Color=8388608|FontID=1|IsHidden=T|Text=*|Name=SHEETPART
|RECORD=41|OwnerIndex=459|IndexInSheet=16|OwnerPartId=-1|Location.X=856|Location.Y=812|Color=8388608|FontID=1|IsHidden=T|Text=RES, 10K, 1%, 1/10W, TF, 0603|Name=DESC
|RECORD=41|OwnerIndex=459|IndexInSheet=17|OwnerPartId=-1|Location.X=864|Location.Y=775|Color=8388608|FontID=2|Text=10K|Name=VALUE
|RECORD=2|OwnerIndex=459|OwnerPartId=1|FormalType=1|Electrical=4|PinConglomerate=35|PinLength=10|Location.X=860|Location.Y=770|Name=1|Designator=1|PinPropagationDelay=0.000000E+000
|RECORD=2|OwnerIndex=459|OwnerPartId=1|FormalType=1|Electrical=4|PinConglomerate=33|PinLength=10|Location.X=860|Location.Y=800|Name=2|Designator=2|PinPropagationDelay=0.000000E+000
|RECORD=6|OwnerIndex=459|IsNotAccesible=T|IndexInSheet=20|OwnerPartId=1|LineWidth=1|Color=16711680|LocationCount=7|X1=860|Y1=800|X2=857|Y2=797|X3=863|Y3=791|X4=857|Y4=785|X5=863|Y5=779|X6=857|Y6=773|X7=860|Y7=770
|RECORD=41|OwnerIndex=459|IndexInSheet=21|OwnerPartId=-1|Location.X=856|Location.Y=812|Color=8388608|FontID=1|IsHidden=T|Text=<VELENTIUM>|Name=VELENTIUM PART NUM
|RECORD=34|OwnerIndex=459|IndexInSheet=-1|OwnerPartId=-1|Location.X=864|Location.Y=787|Color=8388608|FontID=5|Text=R6|Name=Designator|ReadOnlyState=1
|RECORD=41|OwnerIndex=459|IndexInSheet=-1|OwnerPartId=-1|Location.X=856|Location.Y=812|Color=8388608|FontID=2|IsHidden=T|Text==MFG PART NUM|Name=Comment
|RECORD=44|OwnerIndex=459
|RECORD=45|OwnerIndex=486|IndexInSheet=-1|Description=Chip Resistor, 0603, 2-Leads, Body 1.57x0.85mm, IPC Medium Density|UseComponentLibrary=T|ModelName=RESC1608X50N|ModelType=PCBLIB|DatafileCount=1|ModelDatafileEntity0=RESC1608X50N|ModelDatafileKind0=PCBLib|IsCurrent=T|DatalinksLocked=T|DatabaseDatalinksLocked=T|IntegratedModel=T|DatabaseModel=T
|RECORD=46|OwnerIndex=487
|RECORD=48|OwnerIndex=487
|RECORD=1|LibReference=RES_0603_47K|ComponentDescription=RES, 47K, 1%, 1/10W, TF, 0603|PartCount=2|DisplayModeCount=1|IndexInSheet=55|OwnerPartId=-1|Location.X=920|Location.Y=840|Orientation=2|CurrentPartId=1|LibraryPath=*|SourceLibraryName=Resistors.IntLib|TargetFileName=*|AreaColor=11599871|Color=128|PartIDLocked=F|DesignItemId=RES_0603_47K|AllPinCount=2
|RECORD=41|OwnerIndex=490|OwnerPartId=-1|Location.X=868|Location.Y=844|Color=8388608|FontID=2|IsHidden=T|Text=1/22/2014|Name=ModifyDate
|RECORD=41|OwnerIndex=490|IndexInSheet=1|OwnerPartId=-1|Location.X=868|Location.Y=844|Color=8388608|FontID=2|IsHidden=T|Text=ERJ-3EKF4702V|Name=MFG PART NUM
|RECORD=41|OwnerIndex=490|IndexInSheet=2|OwnerPartId=-1|Location.X=868|Location.Y=844|Color=8388608|FontID=2|IsHidden=T|Text=PANASONIC|Name=MFG NAME
|RECORD=41|OwnerIndex=490|IndexInSheet=3|OwnerPartId=-1|Location.X=868|Location.Y=844|Color=8388608|FontID=2|IsHidden=T|Text=RES|Name=CATEGORY
|RECORD=41|OwnerIndex=490|IndexInSheet=4|OwnerPartId=-1|Location.X=868|Location.Y=844|Color=8388608|FontID=2|IsHidden=T|Text=1/22/2014|Name=Date
|RECORD=41|OwnerIndex=490|IndexInSheet=5|OwnerPartId=-1|Location.X=868|Location.Y=844|Color=8388608|FontID=2|IsHidden=T|Text=1%|Name=P1
|RECORD=41|OwnerIndex=490|IndexInSheet=6|OwnerPartId=-1|Location.X=868|Location.Y=844|Color=8388608|FontID=2|IsHidden=T|Text=TF|Name=P3
|RECORD=41|OwnerIndex=490|IndexInSheet=7|OwnerPartId=-1|Location.X=868|Location.Y=844|Color=8388608|FontID=2|IsHidden=T|Text=1/10W|Name=P2
|RECORD=41|OwnerIndex=490|IndexInSheet=8|OwnerPartId=-1|Location.X=868|Location.Y=844|Color=8388608|FontID=2|IsHidden=T|Text=125C|Name=MAXTEMP
|RECORD=41|OwnerIndex=490|IndexInSheet=9|OwnerPartId=-1|Location.X=868|Location.Y=844|Color=8388608|FontID=2|IsHidden=T|Text=-55C|Name=MINTEMP
|RECORD=41|OwnerIndex=490|IndexInSheet=10|OwnerPartId=-1|Location.X=868|Location.Y=844|Color=8388608|FontID=2|IsHidden=T|Text=100PPM|Name=OTHER
|RECORD=41|OwnerIndex=490|IndexInSheet=11|OwnerPartId=-1|Location.X=868|Location.Y=844|Color=8388608|FontID=2|IsHidden=T|Text=0603|Name=SIZE
|RECORD=41|OwnerIndex=490|IndexInSheet=12|OwnerPartId=-1|Location.X=868|Location.Y=844|Color=8388608|FontID=2|IsHidden=T|Text=GENERIC|Name=SUB
|RECORD=41|OwnerIndex=490|IndexInSheet=13|OwnerPartId=-1|Location.X=868|Location.Y=844|Color=8388608|FontID=1|IsHidden=T|Text=*|Name=SHEETPART
|RECORD=41|OwnerIndex=490|IndexInSheet=14|OwnerPartId=-1|Location.X=868|Location.Y=844|Color=8388608|FontID=1|IsHidden=T|Text=RES, 47K, 1%, 1/10W, TF, 0603|Name=DESC
|RECORD=41|OwnerIndex=490|IndexInSheet=15|OwnerPartId=-1|Location.X=868|Location.Y=844|Color=8388608|FontID=1|IsHidden=T|Text=Digi-Key|Name=Supplier 1|ReadOnlyState=3
|RECORD=41|OwnerIndex=490|IndexInSheet=16|OwnerPartId=-1|Location.X=868|Location.Y=844|Color=8388608|FontID=1|IsHidden=T|Text=P47.0KHCT-ND|Name=Supplier Part Number 1|ReadOnlyState=3
|RECORD=41|OwnerIndex=490|IndexInSheet=17|OwnerPartId=-1|Location.X=879|Location.Y=824|Color=8388608|FontID=2|Text=47K|Name=VALUE
|RECORD=2|OwnerIndex=490|OwnerPartId=1|FormalType=1|Electrical=4|PinConglomerate=32|PinLength=10|Location.X=910|Location.Y=840|Name=1|Designator=1|PinPropagationDelay=0.000000E+000
|RECORD=2|OwnerIndex=490|OwnerPartId=1|FormalType=1|Electrical=4|PinConglomerate=34|PinLength=10|Location.X=880|Location.Y=840|Name=2|Designator=2|PinPropagationDelay=0.000000E+000
|RECORD=6|OwnerIndex=490|IsNotAccesible=T|IndexInSheet=20|OwnerPartId=1|LineWidth=1|Color=16711680|LocationCount=7|X1=880|Y1=840|X2=883|Y2=837|X3=889|Y3=843|X4=895|Y4=837|X5=901|Y5=843|X6=907|Y6=837|X7=910|Y7=840
|RECORD=41|OwnerIndex=490|IndexInSheet=21|OwnerPartId=-1|Location.X=868|Location.Y=844|Color=8388608|FontID=1|IsHidden=T|Text=<VELENTIUM>|Name=VELENTIUM PART NUM
|RECORD=34|OwnerIndex=490|IndexInSheet=-1|OwnerPartId=-1|Location.X=879|Location.Y=844|Color=8388608|FontID=5|Text=R4|Name=Designator|ReadOnlyState=1
|RECORD=41|OwnerIndex=490|IndexInSheet=-1|OwnerPartId=-1|Location.X=868|Location.Y=844|Color=8388608|FontID=2|IsHidden=T|Text==MFG PART NUM|Name=Comment
|RECORD=44|OwnerIndex=490
|RECORD=45|OwnerIndex=517|IndexInSheet=-1|Description=Chip Resistor, 0603, 2-Leads, Body 1.57x0.85mm, IPC Medium Density|UseComponentLibrary=T|ModelName=RESC1608X50N|ModelType=PCBLIB|DatafileCount=1|ModelDatafileEntity0=RESC1608X50N|ModelDatafileKind0=PCBLib|IsCurrent=T|DatalinksLocked=T|DatabaseDatalinksLocked=T|IntegratedModel=T|DatabaseModel=T
|RECORD=46|OwnerIndex=518
|RECORD=48|OwnerIndex=518
|RECORD=1|LibReference=CAP_0603_0.01UF_50V|ComponentDescription=CAP, CER, 0.01UF, 50V, 10%, X7R, 0603|PartCount=2|DisplayModeCount=1|IndexInSheet=56|OwnerPartId=-1|Location.X=850|Location.Y=940|Orientation=1|CurrentPartId=1|LibraryPath=*|SourceLibraryName=Capacitors.IntLib|TargetFileName=*|AreaColor=11599871|Color=128|PartIDLocked=F|DesignItemId=CAP_0603_0.01UF_50V|AllPinCount=2
|RECORD=41|OwnerIndex=521|OwnerPartId=-1|Location.X=798|Location.Y=966|Color=8388608|FontID=2|IsHidden=T|Text=CAP, CER|Name=CATEGORY
|RECORD=41|OwnerIndex=521|IndexInSheet=1|OwnerPartId=-1|Location.X=798|Location.Y=966|Color=8388608|FontID=2|IsHidden=T|Text=KEMET|Name=MFG NAME
|RECORD=41|OwnerIndex=521|IndexInSheet=2|OwnerPartId=-1|Location.X=798|Location.Y=966|Color=8388608|FontID=2|IsHidden=T|Text=C0603C103K5RACTU|Name=MFG PART NUM
|RECORD=41|OwnerIndex=521|IndexInSheet=3|OwnerPartId=-1|Location.X=798|Location.Y=966|Color=8388608|FontID=2|IsHidden=T|Text=10/23/2013|Name=MODIFY DATE
|RECORD=41|OwnerIndex=521|IndexInSheet=4|OwnerPartId=-1|Location.X=798|Location.Y=966|Color=8388608|FontID=2|IsHidden=T|Text=7/24/2013|Name=Date
|RECORD=41|OwnerIndex=521|IndexInSheet=5|OwnerPartId=-1|Location.X=798|Location.Y=966|Color=8388608|FontID=2|IsHidden=T|Text=*|Name=SHEETPART
|RECORD=41|OwnerIndex=521|IndexInSheet=6|OwnerPartId=-1|Location.X=798|Location.Y=966|Color=8388608|FontID=2|IsHidden=T|Text=10%|Name=P1
|RECORD=41|OwnerIndex=521|IndexInSheet=7|OwnerPartId=-1|Location.X=798|Location.Y=966|Color=8388608|FontID=2|IsHidden=T|Text=125C|Name=MAXTEMP
|RECORD=41|OwnerIndex=521|IndexInSheet=8|OwnerPartId=-1|Location.X=798|Location.Y=966|Color=8388608|FontID=2|IsHidden=T|Text=-55C|Name=MINTEMP
|RECORD=41|OwnerIndex=521|IndexInSheet=9|OwnerPartId=-1|Location.X=798|Location.Y=966|Color=8388608|FontID=2|IsHidden=T|Name=OTHER
|RECORD=41|OwnerIndex=521|IndexInSheet=10|OwnerPartId=-1|Location.X=798|Location.Y=966|Color=8388608|FontID=2|IsHidden=T|Text=50V|Name=P2
|RECORD=41|OwnerIndex=521|IndexInSheet=11|OwnerPartId=-1|Location.X=798|Location.Y=966|Color=8388608|FontID=2|IsHidden=T|Text=X7R|Name=P3
|RECORD=41|OwnerIndex=521|IndexInSheet=12|OwnerPartId=-1|Location.X=798|Location.Y=966|Color=8388608|FontID=2|IsHidden=T|Text=0603|Name=Size
|RECORD=41|OwnerIndex=521|IndexInSheet=13|OwnerPartId=-1|Location.X=798|Location.Y=966|Color=8388608|FontID=2|IsHidden=T|Name=SUB
|RECORD=41|OwnerIndex=521|IndexInSheet=14|OwnerPartId=-1|Location.X=798|Location.Y=966|Color=8388608|FontID=2|IsHidden=T|Text=Digi-Key|Name=Supplier 1|ReadOnlyState=3
|RECORD=41|OwnerIndex=521|IndexInSheet=15|OwnerPartId=-1|Location.X=798|Location.Y=966|Color=8388608|FontID=2|IsHidden=T|Text=399-1091-1-ND|Name=Supplier Part Number 1|ReadOnlyState=3
|RECORD=41|OwnerIndex=521|IndexInSheet=16|OwnerPartId=-1|Location.X=798|Location.Y=966|Color=8388608|FontID=1|IsHidden=T|Text=CAP, CER, 0.01UF, 50V, 10%, X7R, 0603|Name=DESC
|RECORD=41|OwnerIndex=521|IndexInSheet=17|OwnerPartId=-1|Location.X=809|Location.Y=942|Color=8388608|FontID=2|Text=0.01uF|Name=VALUE
|RECORD=2|OwnerIndex=521|OwnerPartId=1|FormalType=1|Electrical=4|PinConglomerate=32|PinLength=10|Location.X=820|Location.Y=960|Name=2|Designator=2|SwapIdPin=2|SwapIDPart=1|PinPropagationDelay=0.000000E+000
|RECORD=2|OwnerIndex=521|OwnerPartId=1|FormalType=1|Electrical=4|PinConglomerate=34|PinLength=10|Location.X=810|Location.Y=960|Name=1|Designator=1|SwapIdPin=1|SwapIDPart=1|PinPropagationDelay=0.000000E+000
|RECORD=13|OwnerIndex=521|IsNotAccesible=T|IndexInSheet=20|OwnerPartId=1|Location.X=817|Location.X_Frac=50000|Location.Y=960|Corner.X=820|Corner.Y=960|LineWidth=1|Color=16711680
|RECORD=13|OwnerIndex=521|IsNotAccesible=T|IndexInSheet=21|OwnerPartId=1|Location.X=810|Location.Y=960|Corner.X=812|Corner.X_Frac=50000|Corner.Y=960|LineWidth=1|Color=16711680
|RECORD=13|OwnerIndex=521|IsNotAccesible=T|IndexInSheet=22|OwnerPartId=1|Location.X=817|Location.X_Frac=50000|Location.Y=965|Corner.X=817|Corner.X_Frac=50000|Corner.Y=955|LineWidth=1|Color=16711680
|RECORD=13|OwnerIndex=521|IsNotAccesible=T|IndexInSheet=23|OwnerPartId=1|Location.X=812|Location.X_Frac=50000|Location.Y=965|Corner.X=812|Corner.X_Frac=50000|Corner.Y=955|LineWidth=1|Color=16711680
|RECORD=41|OwnerIndex=521|IndexInSheet=24|OwnerPartId=-1|Location.X=798|Location.Y=966|Color=8388608|FontID=1|IsHidden=T|Text=<VALENTIUM>|Name=VALENTIUM PART NUM
|RECORD=34|OwnerIndex=521|IndexInSheet=-1|OwnerPartId=-1|Location.X=809|Location.Y=966|Color=8388608|FontID=5|Text=C4|Name=Designator|ReadOnlyState=1
|RECORD=41|OwnerIndex=521|IndexInSheet=-1|OwnerPartId=-1|Location.X=798|Location.Y=966|Color=8388608|FontID=2|IsHidden=T|Text=CAP_0603_0.01UF_50V|Name=Comment|ReadOnlyState=1
|RECORD=44|OwnerIndex=521
|RECORD=45|OwnerIndex=551|IndexInSheet=-1|Description=Chip Capacitor, 0603, 2-Leads, Body 1.60x0.80mm, IPC Medium Density|UseComponentLibrary=T|ModelName=CAPC1608X10N|ModelType=PCBLIB|DatafileCount=1|ModelDatafileEntity0=CAPC1608X10N|ModelDatafileKind0=PCBLib|IsCurrent=T|DatalinksLocked=T|DatabaseDatalinksLocked=T|IntegratedModel=T|DatabaseModel=T
|RECORD=46|OwnerIndex=552
|RECORD=48|OwnerIndex=552
|RECORD=1|LibReference=PM124SH-100M-RC|ComponentDescription=IND, PWR, 10.uH, 20%, 4A, 0.04DCR, 12.5X12.5MM, SHLD|PartCount=2|DisplayModeCount=1|IndexInSheet=57|OwnerPartId=-1|Location.X=850|Location.Y=870|CurrentPartId=1|LibraryPath=*|SourceLibraryName=Passives.IntLib|TargetFileName=*|AreaColor=11599871|Color=128|PartIDLocked=F|DesignItemId=PM124SH-100M-RC|AllPinCount=2
|RECORD=41|OwnerIndex=555|OwnerPartId=-1|Location.X=850|Location.Y=870|Color=8388608|FontID=2|IsHidden=T|Text=PM124SH-100M-RC|Name=MFG PART NUM
|RECORD=41|OwnerIndex=555|IndexInSheet=1|OwnerPartId=-1|Location.X=850|Location.Y=870|Color=8388608|FontID=2|IsHidden=T|Text=10/23/2013|Name=MODIFY DATE
|RECORD=41|OwnerIndex=555|IndexInSheet=2|OwnerPartId=-1|Location.X=850|Location.Y=870|Color=8388608|FontID=2|IsHidden=T|Text=BOURNS|Name=MFG NAME
|RECORD=41|OwnerIndex=555|IndexInSheet=3|OwnerPartId=-1|Location.X=848|Location.Y=892|Location.Y_Frac=10000|Color=8388608|FontID=2|IsHidden=T|Text=10/23/2013|Name=Date
|RECORD=41|OwnerIndex=555|IndexInSheet=4|OwnerPartId=-1|Location.X=848|Location.Y=892|Location.Y_Frac=10000|Color=8388608|FontID=2|IsHidden=T|Text=IND, PWR|Name=CATEGORY
|RECORD=41|OwnerIndex=555|IndexInSheet=5|OwnerPartId=-1|Location.X=848|Location.Y=898|Color=8388608|FontID=2|IsHidden=T|Text=125C|Name=MAXTEMP
|RECORD=41|OwnerIndex=555|IndexInSheet=6|OwnerPartId=-1|Location.X=848|Location.Y=898|Color=8388608|FontID=2|IsHidden=T|Text=-40C|Name=MINTEMP
|RECORD=41|OwnerIndex=555|IndexInSheet=7|OwnerPartId=-1|Location.X=848|Location.Y=898|Color=8388608|FontID=2|IsHidden=T|Text=SHLD|Name=OTHER
|RECORD=41|OwnerIndex=555|IndexInSheet=8|OwnerPartId=-1|Location.X=848|Location.Y=898|Color=8388608|FontID=2|IsHidden=T|Text=20%|Name=P1
|RECORD=41|OwnerIndex=555|IndexInSheet=9|OwnerPartId=-1|Location.X=848|Location.Y=898|Color=8388608|FontID=2|IsHidden=T|Text=4A|Name=P2
|RECORD=41|OwnerIndex=555|IndexInSheet=10|OwnerPartId=-1|Location.X=848|Location.Y=898|Color=8388608|FontID=2|IsHidden=T|Text=36mOhm|Name=P3
|RECORD=41|OwnerIndex=555|IndexInSheet=11|OwnerPartId=-1|Location.X=848|Location.Y=898|Color=8388608|FontID=2|IsHidden=T|Text=12.5X12.5MM|Name=SIZE
|RECORD=41|OwnerIndex=555|IndexInSheet=12|OwnerPartId=-1|Location.X=848|Location.Y=898|Color=8388608|FontID=2|IsHidden=T|Name=SUB
|RECORD=41|OwnerIndex=555|IndexInSheet=13|OwnerPartId=-1|Location.X=848|Location.Y=857|Color=8388608|FontID=1|IsHidden=T|Text=*|Name=SHEETPART
|RECORD=41|OwnerIndex=555|IndexInSheet=14|OwnerPartId=-1|Location.X=848|Location.Y=902|Color=8388608|FontID=1|IsHidden=T|Text=IND, PWR, 10.uH, 20%, 4A, 0.04DCR, 12.5X12.5MM, SHLD|Name=DESC
|RECORD=41|OwnerIndex=555|IndexInSheet=15|OwnerPartId=-1|Location.X=848|Location.Y=902|Color=8388608|FontID=1|IsHidden=T|Text=Digi-Key|Name=Supplier 1|ReadOnlyState=3
|RECORD=41|OwnerIndex=555|IndexInSheet=16|OwnerPartId=-1|Location.X=848|Location.Y=902|Color=8388608|FontID=1|IsHidden=T|Text=PM124SH-100M-RCCT-ND|Name=Supplier Part Number 1|ReadOnlyState=3
|RECORD=2|OwnerIndex=555|OwnerPartId=1|FormalType=1|Electrical=4|PinConglomerate=32|PinLength=20|Location.X=910|Location.Y=870|Designator=1|PinPropagationDelay=0.000000E+000
|RECORD=2|OwnerIndex=555|OwnerPartId=1|FormalType=1|Electrical=4|PinConglomerate=34|PinLength=20|Location.X=870|Location.Y=870|Designator=2|PinPropagationDelay=0.000000E+000
|RECORD=12|OwnerIndex=555|IsNotAccesible=T|IndexInSheet=19|OwnerPartId=1|Location.X=905|Location.Y=875|Radius=5|LineWidth=1|EndAngle=180.000|Color=16711680
|RECORD=12|OwnerIndex=555|IsNotAccesible=T|IndexInSheet=20|OwnerPartId=1|Location.X=895|Location.Y=875|Radius=5|LineWidth=1|EndAngle=180.000|Color=16711680
|RECORD=12|OwnerIndex=555|IsNotAccesible=T|IndexInSheet=21|OwnerPartId=1|Location.X=885|Location.Y=875|Radius=5|LineWidth=1|EndAngle=180.000|Color=16711680
|RECORD=12|OwnerIndex=555|IsNotAccesible=T|IndexInSheet=22|OwnerPartId=1|Location.X=875|Location.Y=875|Radius=5|LineWidth=1|EndAngle=180.000|Color=16711680
|RECORD=13|OwnerIndex=555|IsNotAccesible=T|IndexInSheet=23|OwnerPartId=1|Location.X=910|Location.Y=875|Corner.X=910|Corner.Y=870|LineWidth=1|Color=16711680
|RECORD=13|OwnerIndex=555|IsNotAccesible=T|IndexInSheet=24|OwnerPartId=1|Location.X=900|Location.Y=875|Corner.X=900|Corner.Y=870|LineWidth=1|Color=16711680
|RECORD=13|OwnerIndex=555|IsNotAccesible=T|IndexInSheet=25|OwnerPartId=1|Location.X=890|Location.Y=875|Corner.X=890|Corner.Y=870|LineWidth=1|Color=16711680
|RECORD=13|OwnerIndex=555|IsNotAccesible=T|IndexInSheet=26|OwnerPartId=1|Location.X=880|Location.Y=875|Corner.X=880|Corner.Y=870|LineWidth=1|Color=16711680
|RECORD=13|OwnerIndex=555|IsNotAccesible=T|IndexInSheet=27|OwnerPartId=1|Location.X=870|Location.Y=875|Corner.X=870|Corner.Y=870|LineWidth=1|Color=16711680
|RECORD=41|OwnerIndex=555|IndexInSheet=28|OwnerPartId=-1|Location.X=869|Location.Y=855|Color=8388608|FontID=2|Text=10.uH|Name=VALUE
|RECORD=41|OwnerIndex=555|IndexInSheet=29|OwnerPartId=-1|Location.X=848|Location.Y=902|Color=8388608|FontID=1|IsHidden=T|Text=<VALENTIUM>|Name=VALENTIUM PART NUM
|RECORD=34|OwnerIndex=555|IndexInSheet=-1|OwnerPartId=-1|Location.X=869|Location.Y=880|Color=8388608|FontID=5|Text=L1|Name=Designator|ReadOnlyState=1
|RECORD=41|OwnerIndex=555|IndexInSheet=-1|OwnerPartId=-1|Location.X=850|Location.Y=870|Color=8388608|FontID=2|IsHidden=T|Text=PM124SH-100M-RC|Name=Comment
|RECORD=44|OwnerIndex=555
|RECORD=45|OwnerIndex=590|IndexInSheet=-1|Description=Footprint not found|UseComponentLibrary=T|ModelName=IND_PM124SH|ModelType=PCBLIB|DatafileCount=1|ModelDatafileEntity0=IND_PM124SH|ModelDatafileKind0=PCBLib|IsCurrent=T|DatalinksLocked=T|DatabaseDatalinksLocked=T|IntegratedModel=T|DatabaseModel=T
|RECORD=46|OwnerIndex=591
|RECORD=48|OwnerIndex=591
|RECORD=1|LibReference=PM124SH-100M-RC|ComponentDescription=IND, PWR, 10.uH, 20%, 4A, 0.04DCR, 12.5X12.5MM, SHLD|PartCount=2|DisplayModeCount=1|IndexInSheet=58|OwnerPartId=-1|Location.X=850|Location.Y=460|CurrentPartId=1|LibraryPath=*|SourceLibraryName=Passives.IntLib|TargetFileName=*|AreaColor=11599871|Color=128|PartIDLocked=F|DesignItemId=PM124SH-100M-RC|AllPinCount=2
|RECORD=41|OwnerIndex=594|OwnerPartId=-1|Location.X=850|Location.Y=460|Color=8388608|FontID=2|IsHidden=T|Text=PM124SH-100M-RC|Name=MFG PART NUM
|RECORD=41|OwnerIndex=594|IndexInSheet=1|OwnerPartId=-1|Location.X=850|Location.Y=460|Color=8388608|FontID=2|IsHidden=T|Text=10/23/2013|Name=MODIFY DATE
|RECORD=41|OwnerIndex=594|IndexInSheet=2|OwnerPartId=-1|Location.X=850|Location.Y=460|Color=8388608|FontID=2|IsHidden=T|Text=BOURNS|Name=MFG NAME
|RECORD=41|OwnerIndex=594|IndexInSheet=3|OwnerPartId=-1|Location.X=848|Location.Y=482|Location.Y_Frac=10000|Color=8388608|FontID=2|IsHidden=T|Text=10/23/2013|Name=Date
|RECORD=41|OwnerIndex=594|IndexInSheet=4|OwnerPartId=-1|Location.X=848|Location.Y=482|Location.Y_Frac=10000|Color=8388608|FontID=2|IsHidden=T|Text=IND, PWR|Name=CATEGORY
|RECORD=41|OwnerIndex=594|IndexInSheet=5|OwnerPartId=-1|Location.X=848|Location.Y=488|Color=8388608|FontID=2|IsHidden=T|Text=125C|Name=MAXTEMP
|RECORD=41|OwnerIndex=594|IndexInSheet=6|OwnerPartId=-1|Location.X=848|Location.Y=488|Color=8388608|FontID=2|IsHidden=T|Text=-40C|Name=MINTEMP
|RECORD=41|OwnerIndex=594|IndexInSheet=7|OwnerPartId=-1|Location.X=848|Location.Y=488|Color=8388608|FontID=2|IsHidden=T|Text=SHLD|Name=OTHER
|RECORD=41|OwnerIndex=594|IndexInSheet=8|OwnerPartId=-1|Location.X=848|Location.Y=488|Color=8388608|FontID=2|IsHidden=T|Text=20%|Name=P1
|RECORD=41|OwnerIndex=594|IndexInSheet=9|OwnerPartId=-1|Location.X=848|Location.Y=488|Color=8388608|FontID=2|IsHidden=T|Text=4A|Name=P2
|RECORD=41|OwnerIndex=594|IndexInSheet=10|OwnerPartId=-1|Location.X=848|Location.Y=488|Color=8388608|FontID=2|IsHidden=T|Text=36mOhm|Name=P3
|RECORD=41|OwnerIndex=594|IndexInSheet=11|OwnerPartId=-1|Location.X=848|Location.Y=488|Color=8388608|FontID=2|IsHidden=T|Text=12.5X12.5MM|Name=SIZE
|RECORD=41|OwnerIndex=594|IndexInSheet=12|OwnerPartId=-1|Location.X=848|Location.Y=488|Color=8388608|FontID=2|IsHidden=T|Name=SUB
|RECORD=41|OwnerIndex=594|IndexInSheet=13|OwnerPartId=-1|Location.X=848|Location.Y=447|Color=8388608|FontID=1|IsHidden=T|Text=*|Name=SHEETPART
|RECORD=41|OwnerIndex=594|IndexInSheet=14|OwnerPartId=-1|Location.X=848|Location.Y=492|Color=8388608|FontID=1|IsHidden=T|Text=IND, PWR, 10.uH, 20%, 4A, 0.04DCR, 12.5X12.5MM, SHLD|Name=DESC
|RECORD=41|OwnerIndex=594|IndexInSheet=15|OwnerPartId=-1|Location.X=848|Location.Y=492|Color=8388608|FontID=1|IsHidden=T|Text=Digi-Key|Name=Supplier 1|ReadOnlyState=3
|RECORD=41|OwnerIndex=594|IndexInSheet=16|OwnerPartId=-1|Location.X=848|Location.Y=492|Color=8388608|FontID=1|IsHidden=T|Text=PM124SH-100M-RCCT-ND|Name=Supplier Part Number 1|ReadOnlyState=3
|RECORD=2|OwnerIndex=594|OwnerPartId=1|FormalType=1|Electrical=4|PinConglomerate=32|PinLength=20|Location.X=910|Location.Y=460|Designator=1|PinPropagationDelay=0.000000E+000
|RECORD=2|OwnerIndex=594|OwnerPartId=1|FormalType=1|Electrical=4|PinConglomerate=34|PinLength=20|Location.X=870|Location.Y=460|Designator=2|PinPropagationDelay=0.000000E+000
|RECORD=12|OwnerIndex=594|IsNotAccesible=T|IndexInSheet=19|OwnerPartId=1|Location.X=905|Location.Y=465|Radius=5|LineWidth=1|EndAngle=180.000|Color=16711680
|RECORD=12|OwnerIndex=594|IsNotAccesible=T|IndexInSheet=20|OwnerPartId=1|Location.X=895|Location.Y=465|Radius=5|LineWidth=1|EndAngle=180.000|Color=16711680
|RECORD=12|OwnerIndex=594|IsNotAccesible=T|IndexInSheet=21|OwnerPartId=1|Location.X=885|Location.Y=465|Radius=5|LineWidth=1|EndAngle=180.000|Color=16711680
|RECORD=12|OwnerIndex=594|IsNotAccesible=T|IndexInSheet=22|OwnerPartId=1|Location.X=875|Location.Y=465|Radius=5|LineWidth=1|EndAngle=180.000|Color=16711680
|RECORD=13|OwnerIndex=594|IsNotAccesible=T|IndexInSheet=23|OwnerPartId=1|Location.X=910|Location.Y=465|Corner.X=910|Corner.Y=460|LineWidth=1|Color=16711680
|RECORD=13|OwnerIndex=594|IsNotAccesible=T|IndexInSheet=24|OwnerPartId=1|Location.X=900|Location.Y=465|Corner.X=900|Corner.Y=460|LineWidth=1|Color=16711680
|RECORD=13|OwnerIndex=594|IsNotAccesible=T|IndexInSheet=25|OwnerPartId=1|Location.X=890|Location.Y=465|Corner.X=890|Corner.Y=460|LineWidth=1|Color=16711680
|RECORD=13|OwnerIndex=594|IsNotAccesible=T|IndexInSheet=26|OwnerPartId=1|Location.X=880|Location.Y=465|Corner.X=880|Corner.Y=460|LineWidth=1|Color=16711680
|RECORD=13|OwnerIndex=594|IsNotAccesible=T|IndexInSheet=27|OwnerPartId=1|Location.X=870|Location.Y=465|Corner.X=870|Corner.Y=460|LineWidth=1|Color=16711680
|RECORD=41|OwnerIndex=594|IndexInSheet=28|OwnerPartId=-1|Location.X=869|Location.Y=445|Color=8388608|FontID=2|Text=10.uH|Name=VALUE
|RECORD=41|OwnerIndex=594|IndexInSheet=29|OwnerPartId=-1|Location.X=848|Location.Y=492|Color=8388608|FontID=1|IsHidden=T|Text=<VALENTIUM>|Name=VALENTIUM PART NUM
|RECORD=34|OwnerIndex=594|IndexInSheet=-1|OwnerPartId=-1|Location.X=869|Location.Y=470|Color=8388608|FontID=5|Text=L2|Name=Designator|ReadOnlyState=1
|RECORD=41|OwnerIndex=594|IndexInSheet=-1|OwnerPartId=-1|Location.X=850|Location.Y=460|Color=8388608|FontID=2|IsHidden=T|Text=PM124SH-100M-RC|Name=Comment
|RECORD=44|OwnerIndex=594
|RECORD=45|OwnerIndex=629|IndexInSheet=-1|Description=Footprint not found|UseComponentLibrary=T|ModelName=IND_PM124SH|ModelType=PCBLIB|DatafileCount=1|ModelDatafileEntity0=IND_PM124SH|ModelDatafileKind0=PCBLib|IsCurrent=T|DatalinksLocked=T|DatabaseDatalinksLocked=T|IntegratedModel=T|DatabaseModel=T
|RECORD=46|OwnerIndex=630
|RECORD=48|OwnerIndex=630
|RECORD=1|LibReference=CAP_0603_0.01UF_50V|ComponentDescription=CAP, CER, 0.01UF, 50V, 10%, X7R, 0603|PartCount=2|DisplayModeCount=1|IndexInSheet=59|OwnerPartId=-1|Location.X=800|Location.Y=540|Orientation=1|CurrentPartId=1|LibraryPath=*|SourceLibraryName=Capacitors.IntLib|TargetFileName=*|AreaColor=11599871|Color=128|PartIDLocked=F|DesignItemId=CAP_0603_0.01UF_50V|AllPinCount=2
|RECORD=41|OwnerIndex=633|OwnerPartId=-1|Location.X=748|Location.Y=566|Color=8388608|FontID=2|IsHidden=T|Text=CAP, CER|Name=CATEGORY
|RECORD=41|OwnerIndex=633|IndexInSheet=1|OwnerPartId=-1|Location.X=748|Location.Y=566|Color=8388608|FontID=2|IsHidden=T|Text=KEMET|Name=MFG NAME
|RECORD=41|OwnerIndex=633|IndexInSheet=2|OwnerPartId=-1|Location.X=748|Location.Y=566|Color=8388608|FontID=2|IsHidden=T|Text=C0603C103K5RACTU|Name=MFG PART NUM
|RECORD=41|OwnerIndex=633|IndexInSheet=3|OwnerPartId=-1|Location.X=748|Location.Y=566|Color=8388608|FontID=2|IsHidden=T|Text=10/23/2013|Name=MODIFY DATE
|RECORD=41|OwnerIndex=633|IndexInSheet=4|OwnerPartId=-1|Location.X=748|Location.Y=566|Color=8388608|FontID=2|IsHidden=T|Text=7/24/2013|Name=Date
|RECORD=41|OwnerIndex=633|IndexInSheet=5|OwnerPartId=-1|Location.X=748|Location.Y=566|Color=8388608|FontID=2|IsHidden=T|Text=*|Name=SHEETPART
|RECORD=41|OwnerIndex=633|IndexInSheet=6|OwnerPartId=-1|Location.X=748|Location.Y=566|Color=8388608|FontID=2|IsHidden=T|Text=10%|Name=P1
|RECORD=41|OwnerIndex=633|IndexInSheet=7|OwnerPartId=-1|Location.X=748|Location.Y=566|Color=8388608|FontID=2|IsHidden=T|Text=125C|Name=MAXTEMP
|RECORD=41|OwnerIndex=633|IndexInSheet=8|OwnerPartId=-1|Location.X=748|Location.Y=566|Color=8388608|FontID=2|IsHidden=T|Text=-55C|Name=MINTEMP
|RECORD=41|OwnerIndex=633|IndexInSheet=9|OwnerPartId=-1|Location.X=748|Location.Y=566|Color=8388608|FontID=2|IsHidden=T|Name=OTHER
|RECORD=41|OwnerIndex=633|IndexInSheet=10|OwnerPartId=-1|Location.X=748|Location.Y=566|Color=8388608|FontID=2|IsHidden=T|Text=50V|Name=P2
|RECORD=41|OwnerIndex=633|IndexInSheet=11|OwnerPartId=-1|Location.X=748|Location.Y=566|Color=8388608|FontID=2|IsHidden=T|Text=X7R|Name=P3
|RECORD=41|OwnerIndex=633|IndexInSheet=12|OwnerPartId=-1|Location.X=748|Location.Y=566|Color=8388608|FontID=2|IsHidden=T|Text=0603|Name=Size
|RECORD=41|OwnerIndex=633|IndexInSheet=13|OwnerPartId=-1|Location.X=748|Location.Y=566|Color=8388608|FontID=2|IsHidden=T|Name=SUB
|RECORD=41|OwnerIndex=633|IndexInSheet=14|OwnerPartId=-1|Location.X=748|Location.Y=566|Color=8388608|FontID=2|IsHidden=T|Text=Digi-Key|Name=Supplier 1|ReadOnlyState=3
|RECORD=41|OwnerIndex=633|IndexInSheet=15|OwnerPartId=-1|Location.X=748|Location.Y=566|Color=8388608|FontID=2|IsHidden=T|Text=399-1091-1-ND|Name=Supplier Part Number 1|ReadOnlyState=3
|RECORD=41|OwnerIndex=633|IndexInSheet=16|OwnerPartId=-1|Location.X=748|Location.Y=566|Color=8388608|FontID=1|IsHidden=T|Text=CAP, CER, 0.01UF, 50V, 10%, X7R, 0603|Name=DESC
|RECORD=41|OwnerIndex=633|IndexInSheet=17|OwnerPartId=-1|Location.X=759|Location.Y=542|Color=8388608|FontID=2|Text=0.01uF|Name=VALUE
|RECORD=2|OwnerIndex=633|OwnerPartId=1|FormalType=1|Electrical=4|PinConglomerate=32|PinLength=10|Location.X=770|Location.Y=560|Name=2|Designator=2|SwapIdPin=2|SwapIDPart=1|PinPropagationDelay=0.000000E+000
|RECORD=2|OwnerIndex=633|OwnerPartId=1|FormalType=1|Electrical=4|PinConglomerate=34|PinLength=10|Location.X=760|Location.Y=560|Name=1|Designator=1|SwapIdPin=1|SwapIDPart=1|PinPropagationDelay=0.000000E+000
|RECORD=13|OwnerIndex=633|IsNotAccesible=T|IndexInSheet=20|OwnerPartId=1|Location.X=767|Location.X_Frac=50000|Location.Y=560|Corner.X=770|Corner.Y=560|LineWidth=1|Color=16711680
|RECORD=13|OwnerIndex=633|IsNotAccesible=T|IndexInSheet=21|OwnerPartId=1|Location.X=760|Location.Y=560|Corner.X=762|Corner.X_Frac=50000|Corner.Y=560|LineWidth=1|Color=16711680
|RECORD=13|OwnerIndex=633|IsNotAccesible=T|IndexInSheet=22|OwnerPartId=1|Location.X=767|Location.X_Frac=50000|Location.Y=565|Corner.X=767|Corner.X_Frac=50000|Corner.Y=555|LineWidth=1|Color=16711680
|RECORD=13|OwnerIndex=633|IsNotAccesible=T|IndexInSheet=23|OwnerPartId=1|Location.X=762|Location.X_Frac=50000|Location.Y=565|Corner.X=762|Corner.X_Frac=50000|Corner.Y=555|LineWidth=1|Color=16711680
|RECORD=41|OwnerIndex=633|IndexInSheet=24|OwnerPartId=-1|Location.X=748|Location.Y=566|Color=8388608|FontID=1|IsHidden=T|Text=<VALENTIUM>|Name=VALENTIUM PART NUM
|RECORD=34|OwnerIndex=633|IndexInSheet=-1|OwnerPartId=-1|Location.X=759|Location.Y=566|Color=8388608|FontID=5|Text=C3|Name=Designator|ReadOnlyState=1
|RECORD=41|OwnerIndex=633|IndexInSheet=-1|OwnerPartId=-1|Location.X=748|Location.Y=566|Color=8388608|FontID=2|IsHidden=T|Text=CAP_0603_0.01UF_50V|Name=Comment|ReadOnlyState=1
|RECORD=44|OwnerIndex=633
|RECORD=45|OwnerIndex=663|IndexInSheet=-1|Description=Chip Capacitor, 0603, 2-Leads, Body 1.60x0.80mm, IPC Medium Density|UseComponentLibrary=T|ModelName=CAPC1608X10N|ModelType=PCBLIB|DatafileCount=1|ModelDatafileEntity0=CAPC1608X10N|ModelDatafileKind0=PCBLib|IsCurrent=T|DatalinksLocked=T|DatabaseDatalinksLocked=T|IntegratedModel=T|DatabaseModel=T
|RECORD=46|OwnerIndex=664
|RECORD=48|OwnerIndex=664
|RECORD=1|LibReference=RES_0603_47K|ComponentDescription=RES, 47K, 1%, 1/10W, TF, 0603|PartCount=2|DisplayModeCount=1|IndexInSheet=60|OwnerPartId=-1|Location.X=590|Location.Y=490|Orientation=1|CurrentPartId=1|LibraryPath=*|SourceLibraryName=Resistors.IntLib|TargetFileName=*|AreaColor=11599871|Color=128|PartIDLocked=F|DesignItemId=RES_0603_47K|AllPinCount=2
|RECORD=41|OwnerIndex=667|OwnerPartId=-1|Location.X=586|Location.Y=542|Color=8388608|FontID=2|IsHidden=T|Text=1/22/2014|Name=ModifyDate
|RECORD=41|OwnerIndex=667|IndexInSheet=1|OwnerPartId=-1|Location.X=586|Location.Y=542|Color=8388608|FontID=2|IsHidden=T|Text=ERJ-3EKF4702V|Name=MFG PART NUM
|RECORD=41|OwnerIndex=667|IndexInSheet=2|OwnerPartId=-1|Location.X=586|Location.Y=542|Color=8388608|FontID=2|IsHidden=T|Text=PANASONIC|Name=MFG NAME
|RECORD=41|OwnerIndex=667|IndexInSheet=3|OwnerPartId=-1|Location.X=586|Location.Y=542|Color=8388608|FontID=2|IsHidden=T|Text=RES|Name=CATEGORY
|RECORD=41|OwnerIndex=667|IndexInSheet=4|OwnerPartId=-1|Location.X=586|Location.Y=542|Color=8388608|FontID=2|IsHidden=T|Text=1/22/2014|Name=Date
|RECORD=41|OwnerIndex=667|IndexInSheet=5|OwnerPartId=-1|Location.X=586|Location.Y=542|Color=8388608|FontID=2|IsHidden=T|Text=1%|Name=P1
|RECORD=41|OwnerIndex=667|IndexInSheet=6|OwnerPartId=-1|Location.X=586|Location.Y=542|Color=8388608|FontID=2|IsHidden=T|Text=TF|Name=P3
|RECORD=41|OwnerIndex=667|IndexInSheet=7|OwnerPartId=-1|Location.X=586|Location.Y=542|Color=8388608|FontID=2|IsHidden=T|Text=1/10W|Name=P2
|RECORD=41|OwnerIndex=667|IndexInSheet=8|OwnerPartId=-1|Location.X=586|Location.Y=542|Color=8388608|FontID=2|IsHidden=T|Text=125C|Name=MAXTEMP
|RECORD=41|OwnerIndex=667|IndexInSheet=9|OwnerPartId=-1|Location.X=586|Location.Y=542|Color=8388608|FontID=2|IsHidden=T|Text=-55C|Name=MINTEMP
|RECORD=41|OwnerIndex=667|IndexInSheet=10|OwnerPartId=-1|Location.X=586|Location.Y=542|Color=8388608|FontID=2|IsHidden=T|Text=100PPM|Name=OTHER
|RECORD=41|OwnerIndex=667|IndexInSheet=11|OwnerPartId=-1|Location.X=586|Location.Y=542|Color=8388608|FontID=2|IsHidden=T|Text=0603|Name=SIZE
|RECORD=41|OwnerIndex=667|IndexInSheet=12|OwnerPartId=-1|Location.X=586|Location.Y=542|Color=8388608|FontID=2|IsHidden=T|Text=GENERIC|Name=SUB
|RECORD=41|OwnerIndex=667|IndexInSheet=13|OwnerPartId=-1|Location.X=586|Location.Y=542|Color=8388608|FontID=1|IsHidden=T|Text=*|Name=SHEETPART
|RECORD=41|OwnerIndex=667|IndexInSheet=14|OwnerPartId=-1|Location.X=586|Location.Y=542|Color=8388608|FontID=1|IsHidden=T|Text=RES, 47K, 1%, 1/10W, TF, 0603|Name=DESC
|RECORD=41|OwnerIndex=667|IndexInSheet=15|OwnerPartId=-1|Location.X=586|Location.Y=542|Color=8388608|FontID=1|IsHidden=T|Text=Digi-Key|Name=Supplier 1|ReadOnlyState=3
|RECORD=41|OwnerIndex=667|IndexInSheet=16|OwnerPartId=-1|Location.X=586|Location.Y=542|Color=8388608|FontID=1|IsHidden=T|Text=P47.0KHCT-ND|Name=Supplier Part Number 1|ReadOnlyState=3
|RECORD=41|OwnerIndex=667|IndexInSheet=17|OwnerPartId=-1|Location.X=594|Location.Y=505|Color=8388608|FontID=2|Text=47K|Name=VALUE
|RECORD=2|OwnerIndex=667|OwnerPartId=1|FormalType=1|Electrical=4|PinConglomerate=35|PinLength=10|Location.X=590|Location.Y=500|Name=1|Designator=1|PinPropagationDelay=0.000000E+000
|RECORD=2|OwnerIndex=667|OwnerPartId=1|FormalType=1|Electrical=4|PinConglomerate=33|PinLength=10|Location.X=590|Location.Y=530|Name=2|Designator=2|PinPropagationDelay=0.000000E+000
|RECORD=6|OwnerIndex=667|IsNotAccesible=T|IndexInSheet=20|OwnerPartId=1|LineWidth=1|Color=16711680|LocationCount=7|X1=590|Y1=530|X2=587|Y2=527|X3=593|Y3=521|X4=587|Y4=515|X5=593|Y5=509|X6=587|Y6=503|X7=590|Y7=500
|RECORD=41|OwnerIndex=667|IndexInSheet=21|OwnerPartId=-1|Location.X=586|Location.Y=542|Color=8388608|FontID=1|IsHidden=T|Text=<VELENTIUM>|Name=VELENTIUM PART NUM
|RECORD=34|OwnerIndex=667|IndexInSheet=-1|OwnerPartId=-1|Location.X=594|Location.Y=517|Color=8388608|FontID=5|Text=R3|Name=Designator|ReadOnlyState=1
|RECORD=41|OwnerIndex=667|IndexInSheet=-1|OwnerPartId=-1|Location.X=586|Location.Y=542|Color=8388608|FontID=2|IsHidden=T|Text==MFG PART NUM|Name=Comment
|RECORD=44|OwnerIndex=667
|RECORD=45|OwnerIndex=694|IndexInSheet=-1|Description=Chip Resistor, 0603, 2-Leads, Body 1.57x0.85mm, IPC Medium Density|UseComponentLibrary=T|ModelName=RESC1608X50N|ModelType=PCBLIB|DatafileCount=1|ModelDatafileEntity0=RESC1608X50N|ModelDatafileKind0=PCBLib|IsCurrent=T|DatalinksLocked=T|DatabaseDatalinksLocked=T|IntegratedModel=T|DatabaseModel=T
|RECORD=46|OwnerIndex=695
|RECORD=48|OwnerIndex=695
|RECORD=1|LibReference=RES_0603_10K|ComponentDescription=RES, 10K, 1%, 1/10W, TF, 0603|PartCount=2|DisplayModeCount=1|IndexInSheet=61|OwnerPartId=-1|Location.X=810|Location.Y=310|Orientation=1|CurrentPartId=1|LibraryPath=*|SourceLibraryName=Resistors.IntLib|TargetFileName=*|AreaColor=11599871|Color=128|PartIDLocked=F|DesignItemId=RES_0603_10K|AllPinCount=2
|RECORD=41|OwnerIndex=698|OwnerPartId=-1|Location.X=806|Location.Y=362|Color=8388608|FontID=2|IsHidden=T|Text=7/25/2013|Name=ModifyDate
|RECORD=41|OwnerIndex=698|IndexInSheet=1|OwnerPartId=-1|Location.X=806|Location.Y=362|Color=8388608|FontID=2|IsHidden=T|Text=ERJ-3EKF1002V|Name=MFG PART NUM
|RECORD=41|OwnerIndex=698|IndexInSheet=2|OwnerPartId=-1|Location.X=806|Location.Y=362|Color=8388608|FontID=2|IsHidden=T|Text=PANASONIC|Name=MFG NAME
|RECORD=41|OwnerIndex=698|IndexInSheet=3|OwnerPartId=-1|Location.X=806|Location.Y=362|Color=8388608|FontID=2|IsHidden=T|Text=RES|Name=CATEGORY
|RECORD=41|OwnerIndex=698|IndexInSheet=4|OwnerPartId=-1|Location.X=806|Location.Y=362|Color=8388608|FontID=2|IsHidden=T|Text=7/26/2013|Name=Date
|RECORD=41|OwnerIndex=698|IndexInSheet=5|OwnerPartId=-1|Location.X=806|Location.Y=362|Color=8388608|FontID=2|IsHidden=T|Text=1%|Name=P1
|RECORD=41|OwnerIndex=698|IndexInSheet=6|OwnerPartId=-1|Location.X=806|Location.Y=362|Color=8388608|FontID=2|IsHidden=T|Text=TF|Name=P3
|RECORD=41|OwnerIndex=698|IndexInSheet=7|OwnerPartId=-1|Location.X=806|Location.Y=362|Color=8388608|FontID=2|IsHidden=T|Text=1/10W|Name=P2
|RECORD=41|OwnerIndex=698|IndexInSheet=8|OwnerPartId=-1|Location.X=806|Location.Y=362|Color=8388608|FontID=2|IsHidden=T|Text=125C|Name=MAXTEMP
|RECORD=41|OwnerIndex=698|IndexInSheet=9|OwnerPartId=-1|Location.X=806|Location.Y=362|Color=8388608|FontID=2|IsHidden=T|Text=-55C|Name=MINTEMP
|RECORD=41|OwnerIndex=698|IndexInSheet=10|OwnerPartId=-1|Location.X=806|Location.Y=362|Color=8388608|FontID=2|IsHidden=T|Text=100PPM|Name=OTHER
|RECORD=41|OwnerIndex=698|IndexInSheet=11|OwnerPartId=-1|Location.X=806|Location.Y=362|Color=8388608|FontID=2|IsHidden=T|Text=0603|Name=SIZE
|RECORD=41|OwnerIndex=698|IndexInSheet=12|OwnerPartId=-1|Location.X=806|Location.Y=362|Color=8388608|FontID=2|IsHidden=T|Text=GENERIC|Name=SUB
|RECORD=41|OwnerIndex=698|IndexInSheet=13|OwnerPartId=-1|Location.X=806|Location.Y=362|Color=8388608|FontID=2|IsHidden=T|Text=Digi-Key|Name=Supplier 1|ReadOnlyState=3
|RECORD=41|OwnerIndex=698|IndexInSheet=14|OwnerPartId=-1|Location.X=806|Location.Y=362|Color=8388608|FontID=2|IsHidden=T|Text=P10.0KHCT-ND|Name=Supplier Part Number 1|ReadOnlyState=3
|RECORD=41|OwnerIndex=698|IndexInSheet=15|OwnerPartId=-1|Location.X=806|Location.Y=362|Color=8388608|FontID=1|IsHidden=T|Text=*|Name=SHEETPART
|RECORD=41|OwnerIndex=698|IndexInSheet=16|OwnerPartId=-1|Location.X=806|Location.Y=362|Color=8388608|FontID=1|IsHidden=T|Text=RES, 10K, 1%, 1/10W, TF, 0603|Name=DESC
|RECORD=41|OwnerIndex=698|IndexInSheet=17|OwnerPartId=-1|Location.X=814|Location.Y=325|Color=8388608|FontID=2|Text=10K|Name=VALUE
|RECORD=2|OwnerIndex=698|OwnerPartId=1|FormalType=1|Electrical=4|PinConglomerate=35|PinLength=10|Location.X=810|Location.Y=320|Name=1|Designator=1|PinPropagationDelay=0.000000E+000
|RECORD=2|OwnerIndex=698|OwnerPartId=1|FormalType=1|Electrical=4|PinConglomerate=33|PinLength=10|Location.X=810|Location.Y=350|Name=2|Designator=2|PinPropagationDelay=0.000000E+000
|RECORD=6|OwnerIndex=698|IsNotAccesible=T|IndexInSheet=20|OwnerPartId=1|LineWidth=1|Color=16711680|LocationCount=7|X1=810|Y1=350|X2=807|Y2=347|X3=813|Y3=341|X4=807|Y4=335|X5=813|Y5=329|X6=807|Y6=323|X7=810|Y7=320
|RECORD=41|OwnerIndex=698|IndexInSheet=21|OwnerPartId=-1|Location.X=806|Location.Y=362|Color=8388608|FontID=1|IsHidden=T|Text=<VELENTIUM>|Name=VELENTIUM PART NUM
|RECORD=34|OwnerIndex=698|IndexInSheet=-1|OwnerPartId=-1|Location.X=814|Location.Y=337|Color=8388608|FontID=5|Text=R7|Name=Designator|ReadOnlyState=1
|RECORD=41|OwnerIndex=698|IndexInSheet=-1|OwnerPartId=-1|Location.X=806|Location.Y=362|Color=8388608|FontID=2|IsHidden=T|Text==MFG PART NUM|Name=Comment
|RECORD=44|OwnerIndex=698
|RECORD=45|OwnerIndex=725|IndexInSheet=-1|Description=Chip Resistor, 0603, 2-Leads, Body 1.57x0.85mm, IPC Medium Density|UseComponentLibrary=T|ModelName=RESC1608X50N|ModelType=PCBLIB|DatafileCount=1|ModelDatafileEntity0=RESC1608X50N|ModelDatafileKind0=PCBLib|IsCurrent=T|DatalinksLocked=T|DatabaseDatalinksLocked=T|IntegratedModel=T|DatabaseModel=T
|RECORD=46|OwnerIndex=726
|RECORD=48|OwnerIndex=726
|RECORD=1|LibReference=RES_0603_2.2K|ComponentDescription=RES, 2.2K, 1%, 1/10W, TF, 0603|PartCount=2|DisplayModeCount=1|IndexInSheet=62|OwnerPartId=-1|Location.X=670|Location.Y=280|CurrentPartId=1|LibraryPath=*|SourceLibraryName=Resistors.IntLib|TargetFileName=*|AreaColor=11599871|Color=128|PartIDLocked=F|DesignItemId=RES_0603_2.2K|AllPinCount=2
|RECORD=41|OwnerIndex=729|OwnerPartId=-1|Location.X=670|Location.Y=280|Color=8388608|FontID=2|IsHidden=T|Text=8/15/2013|Name=ModifyDate
|RECORD=41|OwnerIndex=729|IndexInSheet=1|OwnerPartId=-1|Location.X=670|Location.Y=280|Color=8388608|FontID=2|IsHidden=T|Text=ERJ-3EKF2201V|Name=MFG PART NUM
|RECORD=41|OwnerIndex=729|IndexInSheet=2|OwnerPartId=-1|Location.X=670|Location.Y=280|Color=8388608|FontID=2|IsHidden=T|Text=PANASONIC|Name=MFG NAME
|RECORD=41|OwnerIndex=729|IndexInSheet=3|OwnerPartId=-1|Location.X=670|Location.Y=280|Color=8388608|FontID=2|IsHidden=T|Text=RES|Name=CATEGORY
|RECORD=41|OwnerIndex=729|IndexInSheet=4|OwnerPartId=-1|Location.X=668|Location.Y=290|Color=8388608|FontID=2|IsHidden=T|Text=8/15/2013|Name=Date
|RECORD=41|OwnerIndex=729|IndexInSheet=5|OwnerPartId=-1|Location.X=660|Location.X_Frac=55769|Location.Y=290|Color=8388608|FontID=2|IsHidden=T|Text=1%|Name=P1
|RECORD=41|OwnerIndex=729|IndexInSheet=6|OwnerPartId=-1|Location.X=660|Location.X_Frac=55769|Location.Y=290|Color=8388608|FontID=2|IsHidden=T|Text=TF|Name=P3
|RECORD=41|OwnerIndex=729|IndexInSheet=7|OwnerPartId=-1|Location.X=660|Location.X_Frac=55769|Location.Y=290|Color=8388608|FontID=2|IsHidden=T|Text=1/10W|Name=P2
|RECORD=41|OwnerIndex=729|IndexInSheet=8|OwnerPartId=-1|Location.X=660|Location.X_Frac=55769|Location.Y=290|Color=8388608|FontID=2|IsHidden=T|Text=125C|Name=MAXTEMP
|RECORD=41|OwnerIndex=729|IndexInSheet=9|OwnerPartId=-1|Location.X=660|Location.X_Frac=55769|Location.Y=290|Color=8388608|FontID=2|IsHidden=T|Text=-55C|Name=MINTEMP
|RECORD=41|OwnerIndex=729|IndexInSheet=10|OwnerPartId=-1|Location.X=660|Location.X_Frac=55769|Location.Y=290|Color=8388608|FontID=2|IsHidden=T|Text=100PPM|Name=OTHER
|RECORD=41|OwnerIndex=729|IndexInSheet=11|OwnerPartId=-1|Location.X=660|Location.X_Frac=55769|Location.Y=290|Color=8388608|FontID=2|IsHidden=T|Text=0603|Name=SIZE
|RECORD=41|OwnerIndex=729|IndexInSheet=12|OwnerPartId=-1|Location.X=660|Location.X_Frac=55769|Location.Y=290|Color=8388608|FontID=2|IsHidden=T|Text=GENERIC|Name=SUB
|RECORD=41|OwnerIndex=729|IndexInSheet=13|OwnerPartId=-1|Location.X=655|Location.X_Frac=98077|Location.Y=294|Color=8388608|FontID=2|IsHidden=T|Text=Digi-Key|Name=Supplier 1|ReadOnlyState=3
|RECORD=41|OwnerIndex=729|IndexInSheet=14|OwnerPartId=-1|Location.X=655|Location.X_Frac=98077|Location.Y=294|Color=8388608|FontID=2|IsHidden=T|Text=P2.20KHCT-ND|Name=Supplier Part Number 1|ReadOnlyState=3
|RECORD=41|OwnerIndex=729|IndexInSheet=15|OwnerPartId=-1|Location.X=655|Location.X_Frac=98077|Location.Y=266|Color=8388608|FontID=1|IsHidden=T|Text=*|Name=SHEETPART
|RECORD=41|OwnerIndex=729|IndexInSheet=16|OwnerPartId=-1|Location.X=655|Location.X_Frac=98077|Location.Y=294|Color=8388608|FontID=1|IsHidden=T|Text=RES, 2.2K, 1%, 1/10W, TF, 0603|Name=DESC
|RECORD=41|OwnerIndex=729|IndexInSheet=17|OwnerPartId=-1|Location.X=679|Location.Y=264|Color=8388608|FontID=2|Text=2.2K|Name=VALUE
|RECORD=2|OwnerIndex=729|OwnerPartId=1|FormalType=1|Electrical=4|PinConglomerate=34|PinLength=10|Location.X=680|Location.Y=280|Name=1|Designator=1|PinPropagationDelay=0.000000E+000
|RECORD=2|OwnerIndex=729|OwnerPartId=1|FormalType=1|Electrical=4|PinConglomerate=32|PinLength=10|Location.X=710|Location.Y=280|Name=2|Designator=2|PinPropagationDelay=0.000000E+000
|RECORD=6|OwnerIndex=729|IsNotAccesible=T|IndexInSheet=20|OwnerPartId=1|LineWidth=1|Color=16711680|LocationCount=7|X1=710|Y1=280|X2=707|Y2=283|X3=701|Y3=277|X4=695|Y4=283|X5=689|Y5=277|X6=683|Y6=283|X7=680|Y7=280
|RECORD=41|OwnerIndex=729|IndexInSheet=21|OwnerPartId=-1|Location.X=656|Location.X_Frac=61102|Location.Y=294|Color=8388608|FontID=1|IsHidden=T|Text=<VELENTIUM>|Name=VELENTIUM PART NUM
|RECORD=34|OwnerIndex=729|IndexInSheet=-1|OwnerPartId=-1|Location.X=679|Location.Y=284|Color=8388608|FontID=5|Text=R9|Name=Designator|ReadOnlyState=1
|RECORD=41|OwnerIndex=729|IndexInSheet=-1|OwnerPartId=-1|Location.X=690|Location.Y=270|Color=8388608|FontID=2|IsHidden=T|Text==MFG PART NUM|Name=Comment
|RECORD=44|OwnerIndex=729
|RECORD=45|OwnerIndex=756|IndexInSheet=-1|Description=Chip Resistor, 0603, 2-Leads, Body 1.57x0.85mm, IPC Medium Density|UseComponentLibrary=T|ModelName=RESC1608X50N|ModelType=PCBLIB|DatafileCount=1|ModelDatafileEntity0=RESC1608X50N|ModelDatafileKind0=PCBLib|IsCurrent=T|DatalinksLocked=T|DatabaseDatalinksLocked=T|IntegratedModel=T|DatabaseModel=T
|RECORD=46|OwnerIndex=757
|RECORD=48|OwnerIndex=757
|RECORD=1|LibReference=RES_0603_26.1K|ComponentDescription=RES, 26.1K, 1%, 1/10W, TF, 0603|PartCount=2|DisplayModeCount=1|IndexInSheet=63|OwnerPartId=-1|Location.X=870|Location.Y=430|CurrentPartId=1|LibraryPath=*|SourceLibraryName=Resistors.IntLib|TargetFileName=*|AreaColor=11599871|Color=128|PartIDLocked=F|DesignItemId=RES_0603_26.1K|AllPinCount=2
|RECORD=41|OwnerIndex=760|OwnerPartId=-1|Location.X=870|Location.Y=430|Color=8388608|FontID=2|IsHidden=T|Text=7/25/2013|Name=ModifyDate
|RECORD=41|OwnerIndex=760|IndexInSheet=1|OwnerPartId=-1|Location.X=870|Location.Y=430|Color=8388608|FontID=2|IsHidden=T|Text=ERJ-3EKF2612V|Name=MFG PART NUM
|RECORD=41|OwnerIndex=760|IndexInSheet=2|OwnerPartId=-1|Location.X=870|Location.Y=430|Color=8388608|FontID=2|IsHidden=T|Text=PANASONIC|Name=MFG NAME
|RECORD=41|OwnerIndex=760|IndexInSheet=3|OwnerPartId=-1|Location.X=870|Location.Y=430|Color=8388608|FontID=2|IsHidden=T|Text=RES|Name=CATEGORY
|RECORD=41|OwnerIndex=760|IndexInSheet=4|OwnerPartId=-1|Location.X=868|Location.Y=440|Color=8388608|FontID=2|IsHidden=T|Text=7/26/2013|Name=Date
|RECORD=41|OwnerIndex=760|IndexInSheet=5|OwnerPartId=-1|Location.X=860|Location.X_Frac=55769|Location.Y=440|Color=8388608|FontID=2|IsHidden=T|Text=1%|Name=P1
|RECORD=41|OwnerIndex=760|IndexInSheet=6|OwnerPartId=-1|Location.X=860|Location.X_Frac=55769|Location.Y=440|Color=8388608|FontID=2|IsHidden=T|Text=TF|Name=P3
|RECORD=41|OwnerIndex=760|IndexInSheet=7|OwnerPartId=-1|Location.X=860|Location.X_Frac=55769|Location.Y=440|Color=8388608|FontID=2|IsHidden=T|Text=1/10W|Name=P2
|RECORD=41|OwnerIndex=760|IndexInSheet=8|OwnerPartId=-1|Location.X=860|Location.X_Frac=55769|Location.Y=440|Color=8388608|FontID=2|IsHidden=T|Text=125C|Name=MAXTEMP
|RECORD=41|OwnerIndex=760|IndexInSheet=9|OwnerPartId=-1|Location.X=860|Location.X_Frac=55769|Location.Y=440|Color=8388608|FontID=2|IsHidden=T|Text=-55C|Name=MINTEMP
|RECORD=41|OwnerIndex=760|IndexInSheet=10|OwnerPartId=-1|Location.X=860|Location.X_Frac=55769|Location.Y=440|Color=8388608|FontID=2|IsHidden=T|Text=100PPM|Name=OTHER
|RECORD=41|OwnerIndex=760|IndexInSheet=11|OwnerPartId=-1|Location.X=860|Location.X_Frac=55769|Location.Y=440|Color=8388608|FontID=2|IsHidden=T|Text=0603|Name=SIZE
|RECORD=41|OwnerIndex=760|IndexInSheet=12|OwnerPartId=-1|Location.X=860|Location.X_Frac=55769|Location.Y=440|Color=8388608|FontID=2|IsHidden=T|Text=GENERIC|Name=SUB
|RECORD=41|OwnerIndex=760|IndexInSheet=13|OwnerPartId=-1|Location.X=855|Location.X_Frac=98077|Location.Y=416|Color=8388608|FontID=1|IsHidden=T|Text=*|Name=SHEETPART
|RECORD=41|OwnerIndex=760|IndexInSheet=14|OwnerPartId=-1|Location.X=855|Location.X_Frac=98077|Location.Y=444|Color=8388608|FontID=1|IsHidden=T|Text=RES, 27.1K, 1%, 1/10W, TF, 0603|Name=DESC
|RECORD=41|OwnerIndex=760|IndexInSheet=15|OwnerPartId=-1|Location.X=856|Location.X_Frac=61102|Location.Y=444|Color=8388608|FontID=1|IsHidden=T|Text=<VELENTIUM>|Name=VELENTIUM PART NUM
|RECORD=41|OwnerIndex=760|IndexInSheet=16|OwnerPartId=-1|Location.X=855|Location.X_Frac=98077|Location.Y=444|Color=8388608|FontID=1|IsHidden=T|Text=Digi-Key|Name=Supplier 1|ReadOnlyState=3
|RECORD=41|OwnerIndex=760|IndexInSheet=17|OwnerPartId=-1|Location.X=855|Location.X_Frac=98077|Location.Y=444|Color=8388608|FontID=1|IsHidden=T|Text=P26.1KHCT-ND|Name=Supplier Part Number 1|ReadOnlyState=3
|RECORD=41|OwnerIndex=760|IndexInSheet=18|OwnerPartId=-1|Location.X=879|Location.Y=414|Color=8388608|FontID=2|Text=26.1K|Name=VALUE
|RECORD=2|OwnerIndex=760|OwnerPartId=1|FormalType=1|Electrical=4|PinConglomerate=34|PinLength=10|Location.X=880|Location.Y=430|Name=1|Designator=1|PinPropagationDelay=0.000000E+000
|RECORD=2|OwnerIndex=760|OwnerPartId=1|FormalType=1|Electrical=4|PinConglomerate=32|PinLength=10|Location.X=910|Location.Y=430|Name=2|Designator=2|PinPropagationDelay=0.000000E+000
|RECORD=6|OwnerIndex=760|IsNotAccesible=T|IndexInSheet=21|OwnerPartId=1|LineWidth=1|Color=16711680|LocationCount=7|X1=910|Y1=430|X2=907|Y2=433|X3=901|Y3=427|X4=895|Y4=433|X5=889|Y5=427|X6=883|Y6=433|X7=880|Y7=430
|RECORD=34|OwnerIndex=760|IndexInSheet=-1|OwnerPartId=-1|Location.X=879|Location.Y=434|Color=8388608|FontID=5|Text=R5|Name=Designator|ReadOnlyState=1
|RECORD=41|OwnerIndex=760|IndexInSheet=-1|OwnerPartId=-1|Location.X=890|Location.Y=420|Color=8388608|FontID=2|IsHidden=T|Text==MFG PART NUM|Name=Comment
|RECORD=44|OwnerIndex=760
|RECORD=45|OwnerIndex=787|IndexInSheet=-1|Description=Chip Resistor, 0603, 2-Leads, Body 1.57x0.85mm, IPC Medium Density|UseComponentLibrary=T|ModelName=RESC1608X50N|ModelType=PCBLIB|DatafileCount=1|ModelDatafileEntity0=RESC1608X50N|ModelDatafileKind0=PCBLib|IsCurrent=T|DatalinksLocked=T|DatabaseDatalinksLocked=T|IntegratedModel=T|DatabaseModel=T
|RECORD=46|OwnerIndex=788
|RECORD=48|OwnerIndex=788
|RECORD=1|LibReference=MP1482DS|ComponentDescription=IC, DC/DC, MP1482DS, >4.75VIN, 0.923-15V OUT, SOIC8|PartCount=2|DisplayModeCount=1|IndexInSheet=64|OwnerPartId=-1|Location.X=715|Location.Y=855|CurrentPartId=1|LibraryPath=*|SourceLibraryName=IntegratedCircuits.IntLib|TargetFileName=*|AreaColor=11599871|Color=128|PartIDLocked=F|DesignItemId=MP1482DS|AllPinCount=8
|RECORD=41|OwnerIndex=791|OwnerPartId=-1|Location.X=715|Location.Y=855|Color=8388608|FontID=2|IsHidden=T|Text=MP1482DS-LF|Name=MFG PART NUM
|RECORD=41|OwnerIndex=791|IndexInSheet=1|OwnerPartId=-1|Location.X=715|Location.Y=855|Color=8388608|FontID=2|IsHidden=T|Text=12/27/2005 8:34:25 AM|Name=MODIFY DATE
|RECORD=41|OwnerIndex=791|IndexInSheet=2|OwnerPartId=-1|Location.X=715|Location.Y=855|Color=8388608|FontID=2|IsHidden=T|Text=MPS|Name=MFG NAME
|RECORD=41|OwnerIndex=791|IndexInSheet=3|OwnerPartId=-1|Location.X=643|Location.Y=1030|Color=8388608|FontID=2|IsHidden=T|Text=IC, DC/DC|Name=CATEGORY
|RECORD=41|OwnerIndex=791|IndexInSheet=4|OwnerPartId=-1|Location.X=643|Location.Y=1030|Color=8388608|FontID=2|IsHidden=T|Name=DATE
|RECORD=41|OwnerIndex=791|IndexInSheet=5|OwnerPartId=-1|Location.X=643|Location.Y=1030|Color=8388608|FontID=2|IsHidden=T|Text=+85C|Name=MAXTEMP
|RECORD=41|OwnerIndex=791|IndexInSheet=6|OwnerPartId=-1|Location.X=643|Location.Y=1030|Color=8388608|FontID=2|IsHidden=T|Text=-40C|Name=MINTEMP
|RECORD=41|OwnerIndex=791|IndexInSheet=7|OwnerPartId=-1|Location.X=643|Location.Y=1030|Color=8388608|FontID=2|IsHidden=T|Text=additional spec|Name=OTHER
|RECORD=41|OwnerIndex=791|IndexInSheet=8|OwnerPartId=-1|Location.X=643|Location.Y=1030|Color=8388608|FontID=2|IsHidden=T|Text=>4.75V IN|Name=P1
|RECORD=41|OwnerIndex=791|IndexInSheet=9|OwnerPartId=-1|Location.X=643|Location.Y=1030|Color=8388608|FontID=2|IsHidden=T|Text=0.923-15V OUT|Name=P2
|RECORD=41|OwnerIndex=791|IndexInSheet=10|OwnerPartId=-1|Location.X=643|Location.Y=1030|Color=8388608|FontID=2|IsHidden=T|Text=W|Name=P3
|RECORD=41|OwnerIndex=791|IndexInSheet=11|OwnerPartId=-1|Location.X=643|Location.Y=1030|Color=8388608|FontID=2|IsHidden=T|Text=8SOIC|Name=SIZE
|RECORD=41|OwnerIndex=791|IndexInSheet=12|OwnerPartId=-1|Location.X=643|Location.Y=1030|Color=8388608|FontID=2|IsHidden=T|Name=SUB
|RECORD=41|OwnerIndex=791|IndexInSheet=13|OwnerPartId=-1|Location.X=643|Location.Y=843|Color=8388608|FontID=1|IsHidden=T|Text=*|Name=SHEETPART
|RECORD=41|OwnerIndex=791|IndexInSheet=14|OwnerPartId=-1|Location.X=643|Location.Y=1006|Color=8388608|FontID=1|IsHidden=T|Text=IC, DC/DC, MP1482DS, >4.75VIN, 0.923-15V OUT, SOIC8|Name=DESC
|RECORD=41|OwnerIndex=791|IndexInSheet=15|OwnerPartId=-1|Location.X=643|Location.Y=1006|Color=8388608|FontID=1|IsHidden=T|Text=<V PART NUM>|Name=VELENTIUM PART NUM
|RECORD=41|OwnerIndex=791|IndexInSheet=16|OwnerPartId=-1|Location.X=628|Location.Y=932|Color=8388608|FontID=1|IsHidden=T|Text=Digi-Key|Name=Supplier 1|ReadOnlyState=3
|RECORD=41|OwnerIndex=791|IndexInSheet=17|OwnerPartId=-1|Location.X=628|Location.Y=932|Color=8388608|FontID=1|IsHidden=T|Text=1589-1524-1-ND|Name=Supplier Part Number 1|ReadOnlyState=3
|RECORD=41|OwnerIndex=791|IndexInSheet=18|OwnerPartId=-1|Location.X=790|Location.Y=890|Color=8388608|FontID=2|Text=MP1482DS|Name=VALUE
|RECORD=14|OwnerIndex=791|IsNotAccesible=T|IndexInSheet=19|OwnerPartId=1|Location.X=660|Location.Y=810|Corner.X=770|Corner.Y=900|LineWidth=1|Color=128|AreaColor=11599871|IsSolid=T|Transparent=T
|RECORD=2|OwnerIndex=791|OwnerPartId=1|FormalType=1|Electrical=4|PinConglomerate=57|PinLength=30|Location.X=740|Location.Y=900|Name=BS|Designator=1|SwapIDPart=Ž&Ž||PinPropagationDelay=0.000000E+000
|RECORD=2|OwnerIndex=791|OwnerPartId=1|FormalType=1|Electrical=4|PinConglomerate=57|PinLength=30|Location.X=690|Location.Y=900|Name=IN|Designator=2|SwapIDPart=Ž&Ž||PinPropagationDelay=0.000000E+000
|RECORD=2|OwnerIndex=791|OwnerPartId=1|FormalType=1|Electrical=4|PinConglomerate=56|PinLength=30|Location.X=770|Location.Y=870|Name=SW|Designator=3|SwapIDPart=Ž&Ž||PinPropagationDelay=0.000000E+000
|RECORD=2|OwnerIndex=791|OwnerPartId=1|FormalType=1|Electrical=4|PinConglomerate=56|PinLength=30|Location.X=770|Location.Y=840|Name=FB|Designator=5|SwapIDPart=Ž&Ž||PinPropagationDelay=0.000000E+000
|RECORD=2|OwnerIndex=791|OwnerPartId=1|FormalType=1|Electrical=4|PinConglomerate=58|PinLength=30|Location.X=660|Location.Y=870|Name=EN|Designator=7|SwapIDPart=Ž&Ž||PinPropagationDelay=0.000000E+000
|RECORD=2|OwnerIndex=791|OwnerPartId=1|FormalType=1|Electrical=4|PinConglomerate=58|PinLength=30|Location.X=660|Location.Y=840|Name=SS|Designator=8|SwapIDPart=Ž&Ž||PinPropagationDelay=0.000000E+000
|RECORD=2|OwnerIndex=791|OwnerPartId=1|FormalType=1|Electrical=4|PinConglomerate=59|PinLength=30|Location.X=690|Location.Y=810|Name=GND|Designator=4|SwapIDPart=Ž&Ž||PinPropagationDelay=0.000000E+000
|RECORD=2|OwnerIndex=791|OwnerPartId=1|FormalType=1|Electrical=4|PinConglomerate=59|PinLength=30|Location.X=740|Location.Y=810|Name=COMP|Designator=6|SwapIDPart=Ž&Ž||PinPropagationDelay=0.000000E+000
|RECORD=34|OwnerIndex=791|IndexInSheet=-1|OwnerPartId=-1|Location.X=790|Location.Y=900|Color=8388608|FontID=5|Text=U1|Name=Designator|ReadOnlyState=1
|RECORD=41|OwnerIndex=791|IndexInSheet=-1|OwnerPartId=-1|Location.X=675|Location.Y=1015|Color=8388608|FontID=2|IsHidden=T|Text=MP1482DS-LF|Name=Comment
|RECORD=44|OwnerIndex=791
|RECORD=45|OwnerIndex=830|IndexInSheet=-1|Description=SOIC127P600X175-8N|UseComponentLibrary=T|ModelName=SOIC127P600X175-8N|ModelType=PCBLIB|DatafileCount=1|ModelDatafileEntity0=SOIC127P600X175-8N|ModelDatafileKind0=PCBLib|IsCurrent=T|DatalinksLocked=T|DatabaseDatalinksLocked=T|IntegratedModel=T|DatabaseModel=T
|RECORD=46|OwnerIndex=831
|RECORD=48|OwnerIndex=831
|RECORD=1|LibReference=MP1482DS|ComponentDescription=IC, DC/DC, MP1482DS, >4.75VIN, 0.923-15V OUT, SOIC8|PartCount=2|DisplayModeCount=1|IndexInSheet=65|OwnerPartId=-1|Location.X=695|Location.Y=445|CurrentPartId=1|LibraryPath=*|SourceLibraryName=IntegratedCircuits.IntLib|TargetFileName=*|AreaColor=11599871|Color=128|PartIDLocked=F|DesignItemId=MP1482DS|AllPinCount=8
|RECORD=41|OwnerIndex=834|OwnerPartId=-1|Location.X=695|Location.Y=445|Color=8388608|FontID=2|IsHidden=T|Text=MP1482DS-LF|Name=MFG PART NUM
|RECORD=41|OwnerIndex=834|IndexInSheet=1|OwnerPartId=-1|Location.X=695|Location.Y=445|Color=8388608|FontID=2|IsHidden=T|Text=12/27/2005 8:34:25 AM|Name=MODIFY DATE
|RECORD=41|OwnerIndex=834|IndexInSheet=2|OwnerPartId=-1|Location.X=695|Location.Y=445|Color=8388608|FontID=2|IsHidden=T|Text=MPS|Name=MFG NAME
|RECORD=41|OwnerIndex=834|IndexInSheet=3|OwnerPartId=-1|Location.X=623|Location.Y=620|Color=8388608|FontID=2|IsHidden=T|Text=IC, DC/DC|Name=CATEGORY
|RECORD=41|OwnerIndex=834|IndexInSheet=4|OwnerPartId=-1|Location.X=623|Location.Y=620|Color=8388608|FontID=2|IsHidden=T|Name=DATE
|RECORD=41|OwnerIndex=834|IndexInSheet=5|OwnerPartId=-1|Location.X=623|Location.Y=620|Color=8388608|FontID=2|IsHidden=T|Text=+85C|Name=MAXTEMP
|RECORD=41|OwnerIndex=834|IndexInSheet=6|OwnerPartId=-1|Location.X=623|Location.Y=620|Color=8388608|FontID=2|IsHidden=T|Text=-40C|Name=MINTEMP
|RECORD=41|OwnerIndex=834|IndexInSheet=7|OwnerPartId=-1|Location.X=623|Location.Y=620|Color=8388608|FontID=2|IsHidden=T|Text=additional spec|Name=OTHER
|RECORD=41|OwnerIndex=834|IndexInSheet=8|OwnerPartId=-1|Location.X=623|Location.Y=620|Color=8388608|FontID=2|IsHidden=T|Text=>4.75V IN|Name=P1
|RECORD=41|OwnerIndex=834|IndexInSheet=9|OwnerPartId=-1|Location.X=623|Location.Y=620|Color=8388608|FontID=2|IsHidden=T|Text=0.923-15V OUT|Name=P2
|RECORD=41|OwnerIndex=834|IndexInSheet=10|OwnerPartId=-1|Location.X=623|Location.Y=620|Color=8388608|FontID=2|IsHidden=T|Text=W|Name=P3
|RECORD=41|OwnerIndex=834|IndexInSheet=11|OwnerPartId=-1|Location.X=623|Location.Y=620|Color=8388608|FontID=2|IsHidden=T|Text=8SOIC|Name=SIZE
|RECORD=41|OwnerIndex=834|IndexInSheet=12|OwnerPartId=-1|Location.X=623|Location.Y=620|Color=8388608|FontID=2|IsHidden=T|Name=SUB
|RECORD=41|OwnerIndex=834|IndexInSheet=13|OwnerPartId=-1|Location.X=623|Location.Y=433|Color=8388608|FontID=1|IsHidden=T|Text=*|Name=SHEETPART
|RECORD=41|OwnerIndex=834|IndexInSheet=14|OwnerPartId=-1|Location.X=623|Location.Y=596|Color=8388608|FontID=1|IsHidden=T|Text=IC, DC/DC, MP1482DS, >4.75VIN, 0.923-15V OUT, SOIC8|Name=DESC
|RECORD=41|OwnerIndex=834|IndexInSheet=15|OwnerPartId=-1|Location.X=623|Location.Y=596|Color=8388608|FontID=1|IsHidden=T|Text=<V PART NUM>|Name=VELENTIUM PART NUM
|RECORD=41|OwnerIndex=834|IndexInSheet=16|OwnerPartId=-1|Location.X=608|Location.Y=522|Color=8388608|FontID=1|IsHidden=T|Text=Digi-Key|Name=Supplier 1|ReadOnlyState=3
|RECORD=41|OwnerIndex=834|IndexInSheet=17|OwnerPartId=-1|Location.X=608|Location.Y=522|Color=8388608|FontID=1|IsHidden=T|Text=1589-1524-1-ND|Name=Supplier Part Number 1|ReadOnlyState=3
|RECORD=41|OwnerIndex=834|IndexInSheet=18|OwnerPartId=-1|Location.X=750|Location.Y=480|Color=8388608|FontID=2|Text=MP1482DS|Name=VALUE
|RECORD=14|OwnerIndex=834|IsNotAccesible=T|IndexInSheet=19|OwnerPartId=1|Location.X=640|Location.Y=400|Corner.X=750|Corner.Y=490|LineWidth=1|Color=128|AreaColor=11599871|IsSolid=T|Transparent=T
|RECORD=2|OwnerIndex=834|OwnerPartId=1|FormalType=1|Electrical=4|PinConglomerate=57|PinLength=30|Location.X=720|Location.Y=490|Name=BS|Designator=1|SwapIDPart=Ž&Ž||PinPropagationDelay=0.000000E+000
|RECORD=2|OwnerIndex=834|OwnerPartId=1|FormalType=1|Electrical=4|PinConglomerate=57|PinLength=30|Location.X=670|Location.Y=490|Name=IN|Designator=2|SwapIDPart=Ž&Ž||PinPropagationDelay=0.000000E+000
|RECORD=2|OwnerIndex=834|OwnerPartId=1|FormalType=1|Electrical=4|PinConglomerate=56|PinLength=30|Location.X=750|Location.Y=460|Name=SW|Designator=3|SwapIDPart=Ž&Ž||PinPropagationDelay=0.000000E+000
|RECORD=2|OwnerIndex=834|OwnerPartId=1|FormalType=1|Electrical=4|PinConglomerate=56|PinLength=30|Location.X=750|Location.Y=430|Name=FB|Designator=5|SwapIDPart=Ž&Ž||PinPropagationDelay=0.000000E+000
|RECORD=2|OwnerIndex=834|OwnerPartId=1|FormalType=1|Electrical=4|PinConglomerate=58|PinLength=30|Location.X=640|Location.Y=460|Name=EN|Designator=7|SwapIDPart=Ž&Ž||PinPropagationDelay=0.000000E+000
|RECORD=2|OwnerIndex=834|OwnerPartId=1|FormalType=1|Electrical=4|PinConglomerate=58|PinLength=30|Location.X=640|Location.Y=430|Name=SS|Designator=8|SwapIDPart=Ž&Ž||PinPropagationDelay=0.000000E+000
|RECORD=2|OwnerIndex=834|OwnerPartId=1|FormalType=1|Electrical=4|PinConglomerate=59|PinLength=30|Location.X=670|Location.Y=400|Name=GND|Designator=4|SwapIDPart=Ž&Ž||PinPropagationDelay=0.000000E+000
|RECORD=2|OwnerIndex=834|OwnerPartId=1|FormalType=1|Electrical=4|PinConglomerate=59|PinLength=30|Location.X=720|Location.Y=400|Name=COMP|Designator=6|SwapIDPart=Ž&Ž||PinPropagationDelay=0.000000E+000
|RECORD=34|OwnerIndex=834|IndexInSheet=-1|OwnerPartId=-1|Location.X=750|Location.Y=490|Color=8388608|FontID=5|Text=U2|Name=Designator|ReadOnlyState=1
|RECORD=41|OwnerIndex=834|IndexInSheet=-1|OwnerPartId=-1|Location.X=655|Location.Y=605|Color=8388608|FontID=2|IsHidden=T|Text=MP1482DS-LF|Name=Comment
|RECORD=44|OwnerIndex=834
|RECORD=45|OwnerIndex=873|IndexInSheet=-1|Description=SOIC127P600X175-8N|UseComponentLibrary=T|ModelName=SOIC127P600X175-8N|ModelType=PCBLIB|DatafileCount=1|ModelDatafileEntity0=SOIC127P600X175-8N|ModelDatafileKind0=PCBLib|IsCurrent=T|DatalinksLocked=T|DatabaseDatalinksLocked=T|IntegratedModel=T|DatabaseModel=T
|RECORD=46|OwnerIndex=874
|RECORD=48|OwnerIndex=874
|RECORD=17|IndexInSheet=66|OwnerPartId=-1|ShowNetName=T|Location.X=140|Location.Y=930|Orientation=1|Color=128|FontID=1|Text=+12V_PCIE
|RECORD=1|LibReference=FUSE_0603_2.00A|ComponentDescription=FUSE SLOW 2.00A 32V M 0603|PartCount=2|DisplayModeCount=1|IndexInSheet=67|OwnerPartId=-1|Location.X=230|Location.Y=900|CurrentPartId=1|LibraryPath=*|SourceLibraryName=Passives.IntLib|TargetFileName=*|AreaColor=11599871|Color=128|PartIDLocked=F|DesignItemId=FUSE_0603_2.00A|AllPinCount=2
|RECORD=41|OwnerIndex=878|OwnerPartId=-1|Location.X=230|Location.Y=900|Color=8388608|FontID=2|IsHidden=T|Text=SF-0603S200-2|Name=MFG PART NUM
|RECORD=41|OwnerIndex=878|IndexInSheet=1|OwnerPartId=-1|Location.X=230|Location.Y=900|Color=8388608|FontID=2|IsHidden=T|Text=9/4/2013|Name=MODIFY DATE
|RECORD=41|OwnerIndex=878|IndexInSheet=2|OwnerPartId=-1|Location.X=230|Location.Y=900|Color=8388608|FontID=2|IsHidden=T|Text=BOURNS|Name=MFG NAME
|RECORD=41|OwnerIndex=878|IndexInSheet=3|OwnerPartId=-1|Location.X=230|Location.Y=900|Color=8388608|FontID=2|IsHidden=T|Text=FUSE|Name=CATEGORY
|RECORD=41|OwnerIndex=878|IndexInSheet=4|OwnerPartId=-1|Location.X=228|Location.Y=917|Color=8388608|FontID=2|IsHidden=T|Text=20 OCT 15|Name=DATE
|RECORD=41|OwnerIndex=878|IndexInSheet=5|OwnerPartId=-1|Location.X=228|Location.Y=917|Color=8388608|FontID=2|IsHidden=T|Text=105C|Name=MAXTEMP
|RECORD=41|OwnerIndex=878|IndexInSheet=6|OwnerPartId=-1|Location.X=228|Location.Y=917|Color=8388608|FontID=2|IsHidden=T|Text=-40C|Name=MINTEMP
|RECORD=41|OwnerIndex=878|IndexInSheet=7|OwnerPartId=-1|Location.X=228|Location.Y=917|Color=8388608|FontID=2|IsHidden=T|Text=UL E141069|Name=OTHER
|RECORD=41|OwnerIndex=878|IndexInSheet=8|OwnerPartId=-1|Location.X=228|Location.Y=917|Color=8388608|FontID=2|IsHidden=T|Text=SLOW BLO|Name=P1
|RECORD=41|OwnerIndex=878|IndexInSheet=9|OwnerPartId=-1|Location.X=228|Location.Y=917|Color=8388608|FontID=2|IsHidden=T|Text=32V|Name=P2
|RECORD=41|OwnerIndex=878|IndexInSheet=10|OwnerPartId=-1|Location.X=228|Location.Y=917|Color=8388608|FontID=2|IsHidden=T|Text=M|Name=P3
|RECORD=41|OwnerIndex=878|IndexInSheet=11|OwnerPartId=-1|Location.X=228|Location.Y=917|Color=8388608|FontID=2|IsHidden=T|Text=0603|Name=SIZE
|RECORD=41|OwnerIndex=878|IndexInSheet=12|OwnerPartId=-1|Location.X=228|Location.Y=917|Color=8388608|FontID=2|IsHidden=T|Name=SUB
|RECORD=41|OwnerIndex=878|IndexInSheet=13|OwnerPartId=-1|Location.X=228|Location.Y=873|Color=8388608|FontID=1|IsHidden=T|Text=*|Name=SHEETPART
|RECORD=41|OwnerIndex=878|IndexInSheet=14|OwnerPartId=-1|Location.X=228|Location.Y=921|Color=8388608|FontID=1|IsHidden=T|Text=FUSE SLOW 1.25A 32V M 0603|Name=DESC
|RECORD=41|OwnerIndex=878|IndexInSheet=15|OwnerPartId=-1|Location.X=228|Location.Y=921|Color=8388608|FontID=1|IsHidden=T|Text=<VALENTIUM>|Name=VALENTIUM PART NUM
|RECORD=41|OwnerIndex=878|IndexInSheet=16|OwnerPartId=-1|Location.X=228|Location.Y=921|Color=8388608|FontID=1|IsHidden=T|Text=Digi-Key|Name=Supplier 1|ReadOnlyState=3
|RECORD=2|OwnerIndex=878|OwnerPartId=1|FormalType=1|Electrical=4|PinConglomerate=34|PinLength=20|Location.X=250|Location.Y=900|Name=1|Designator=1|SwapIdPin=1|SwapIDPart=1|PinPropagationDelay=0.000000E+000
|RECORD=2|OwnerIndex=878|OwnerPartId=1|FormalType=1|Electrical=4|PinConglomerate=32|PinLength=20|Location.X=270|Location.Y=900|Name=2|Designator=2|SwapIdPin=2|SwapIDPart=1|PinPropagationDelay=0.000000E+000
|RECORD=12|OwnerIndex=878|IsNotAccesible=T|IndexInSheet=19|OwnerPartId=1|Location.X=265|Location.Y=900|Radius=5|LineWidth=1|StartAngle=180.000|Color=16711680
|RECORD=12|OwnerIndex=878|IsNotAccesible=T|IndexInSheet=20|OwnerPartId=1|Location.X=255|Location.Y=900|Radius=5|LineWidth=1|EndAngle=180.000|Color=16711680
|RECORD=41|OwnerIndex=878|IndexInSheet=21|OwnerPartId=-1|Location.X=248|Location.Y=883|Color=8388608|FontID=2|Text=2.00A|Name=VALUE
|RECORD=8|OwnerIndex=878|IsNotAccesible=T|IndexInSheet=22|OwnerPartId=1|Location.X=250|Location.Y=900|Radius=2|SecondaryRadius=2|LineWidth=1|Color=16711680|AreaColor=16777215|IsSolid=T
|RECORD=8|OwnerIndex=878|IsNotAccesible=T|IndexInSheet=23|OwnerPartId=1|Location.X=270|Location.Y=900|Radius=2|SecondaryRadius=2|LineWidth=1|Color=16711680|AreaColor=16777215|IsSolid=T
|RECORD=41|OwnerIndex=878|IndexInSheet=24|OwnerPartId=-1|Location.X=248|Location.Y=873|Color=8388608|FontID=1|IsHidden=T|Text=SF-0603S200-2CT-ND|Name=Supplier Part Number 1|ReadOnlyState=3
|RECORD=34|OwnerIndex=878|IndexInSheet=-1|OwnerPartId=-1|Location.X=248|Location.Y=905|Color=8388608|FontID=5|Text=F1|Name=Designator|ReadOnlyState=1
|RECORD=41|OwnerIndex=878|IndexInSheet=-1|OwnerPartId=-1|Location.X=270|Location.Y=877|Location.Y_Frac=10000|Color=8388608|FontID=2|IsHidden=T|Text=FUSE_0603_2.00A|Name=Comment
|RECORD=44|OwnerIndex=878
|RECORD=45|OwnerIndex=908|IndexInSheet=-1|Description=Chip Fuse, 0603, 2-Leads, Body 1.60x0.81mm, IPC Medium Density|UseComponentLibrary=T|ModelName=FUSM1608X60N|ModelType=PCBLIB|DatafileCount=1|ModelDatafileEntity0=FUSM1608X60N|ModelDatafileKind0=PCBLib|IsCurrent=T|DatalinksLocked=T|DatabaseDatalinksLocked=T|IntegratedModel=T|DatabaseModel=T
|RECORD=46|OwnerIndex=909
|RECORD=48|OwnerIndex=909
|RECORD=1|LibReference=CAP|ComponentDescription=C0603X104K5RACAUTO|PartCount=2|DisplayModeCount=2|IndexInSheet=68|OwnerPartId=-1|Location.X=370|Location.Y=840|Orientation=1|CurrentPartId=1|SourceLibraryName=Altium Content Vault|TargetFileName=*|AreaColor=11599871|Color=128|PartIDLocked=F|DesignItemId=CMP-2006-00003-1|AllPinCount=2
|RECORD=2|OwnerIndex=912|OwnerPartId=1|OwnerPartDisplayMode=1|FormalType=1|Electrical=4|PinConglomerate=35|PinLength=10|Location.X=380|Location.Y=840|Name=1|Designator=1|PinPropagationDelay=0.000000E+000
|RECORD=2|OwnerIndex=912|OwnerPartId=1|OwnerPartDisplayMode=1|FormalType=1|Electrical=4|PinConglomerate=33|PinLength=10|Location.X=380|Location.Y=850|Name=2|Designator=2|PinPropagationDelay=0.000000E+000
|RECORD=13|OwnerIndex=912|IsNotAccesible=T|IndexInSheet=2|OwnerPartId=1|OwnerPartDisplayMode=1|Location.X=388|Location.Y=840|Corner.X=372|Corner.Y=840|LineWidth=1|Color=16711680
|RECORD=13|OwnerIndex=912|IsNotAccesible=T|IndexInSheet=3|OwnerPartId=1|OwnerPartDisplayMode=1|Location.X=380|Location.Y=844|Corner.X=380|Corner.Y=850|LineWidth=1|Color=16711680
|RECORD=12|OwnerIndex=912|IsNotAccesible=T|IndexInSheet=4|OwnerPartId=1|OwnerPartDisplayMode=1|Location.X=380|Location.Y=860|Radius=16|LineWidth=1|StartAngle=241.000|EndAngle=270.000|Color=16711680
|RECORD=12|OwnerIndex=912|IsNotAccesible=T|IndexInSheet=5|OwnerPartId=1|OwnerPartDisplayMode=1|Location.X=380|Location.Y=860|Radius=16|LineWidth=1|StartAngle=270.000|EndAngle=299.000|Color=16711680
|RECORD=2|OwnerIndex=912|OwnerPartId=1|FormalType=1|Electrical=4|PinConglomerate=35|PinLength=10|Location.X=380|Location.Y=840|Name=1|Designator=1|PinPropagationDelay=0.000000E+000
|RECORD=2|OwnerIndex=912|OwnerPartId=1|FormalType=1|Electrical=4|PinConglomerate=33|PinLength=10|Location.X=380|Location.Y=850|Name=2|Designator=2|PinPropagationDelay=0.000000E+000
|RECORD=13|OwnerIndex=912|IsNotAccesible=T|IndexInSheet=8|OwnerPartId=1|Location.X=372|Location.Y=847|Corner.X=388|Corner.Y=847|LineWidth=1|Color=16711680
|RECORD=13|OwnerIndex=912|IsNotAccesible=T|IndexInSheet=9|OwnerPartId=1|Location.X=388|Location.Y=843|Corner.X=372|Corner.Y=843|LineWidth=1|Color=16711680
|RECORD=6|OwnerIndex=912|IsNotAccesible=T|IndexInSheet=10|OwnerPartId=1|LineWidth=1|Color=16711680|LocationCount=2|X1=380|Y1=840|X2=380|Y2=843
|RECORD=6|OwnerIndex=912|IsNotAccesible=T|IndexInSheet=11|OwnerPartId=1|LineWidth=1|Color=16711680|LocationCount=2|X1=380|Y1=850|X2=380|Y2=847
|RECORD=41|OwnerIndex=912|IndexInSheet=12|OwnerPartId=-1|Location.X=371|Location.Y=862|Color=8388608|FontID=1|IsHidden=T|Text=Kemet|Name=Manufacturer
|RECORD=41|OwnerIndex=912|IndexInSheet=13|OwnerPartId=-1|Location.X=371|Location.Y=862|Color=8388608|FontID=1|IsHidden=T|Text=C0603X104K5RACAUTO|Name=Part Number
|RECORD=34|OwnerIndex=912|IndexInSheet=-1|OwnerPartId=-1|Location.X=389|Location.Y=841|Color=8388608|FontID=5|Text=C2|Name=Designator|ReadOnlyState=1
|RECORD=41|OwnerIndex=912|IndexInSheet=-1|OwnerPartId=-1|Location.X=389|Location.Y=831|Color=8388608|FontID=5|Text=0.1uF|Name=Comment
|RECORD=44|OwnerIndex=912
|RECORD=45|OwnerIndex=933|IndexInSheet=-1|Description=Chip Capacitor, 2-Leads, Body 1.60x0.80mm, IPC Low Density|UseComponentLibrary=T|ModelName=CAPC1608X87X45ML20T05|ModelType=PCBLIB|DatafileCount=1|ModelDatafileEntity0=CAPC1608X87X45ML20T05|ModelDatafileKind0=PCBLib|IsCurrent=T|DatalinksLocked=T|DatabaseDatalinksLocked=T
|RECORD=46|OwnerIndex=934
|RECORD=48|OwnerIndex=934
|RECORD=41|OwnerIndex=936|IndexInSheet=-1|OwnerPartId=-1|Color=8388608|FontID=1|Text=2D|Name=Available Preview Images
|RECORD=45|OwnerIndex=933|IndexInSheet=-1|Description=Chip Capacitor, 2-Leads, Body 1.60x0.80mm, IPC High Density|UseComponentLibrary=T|ModelName=CAPC1608X87X45LL20T05|ModelType=PCBLIB|DatafileCount=1|ModelDatafileEntity0=CAPC1608X87X45LL20T05|ModelDatafileKind0=PCBLib|DatalinksLocked=T|DatabaseDatalinksLocked=T
|RECORD=46|OwnerIndex=938
|RECORD=48|OwnerIndex=938
|RECORD=41|OwnerIndex=940|IndexInSheet=-1|OwnerPartId=-1|Color=8388608|FontID=1|Text=2D|Name=Available Preview Images
|RECORD=45|OwnerIndex=933|IndexInSheet=-1|Description=Chip Capacitor, 2-Leads, Body 1.60x0.80mm, IPC Medium Density|UseComponentLibrary=T|ModelName=CAPC1608X87X45NL20T05|ModelType=PCBLIB|DatafileCount=1|ModelDatafileEntity0=CAPC1608X87X45NL20T05|ModelDatafileKind0=PCBLib|DatalinksLocked=T|DatabaseDatalinksLocked=T
|RECORD=46|OwnerIndex=942
|RECORD=48|OwnerIndex=942
|RECORD=41|OwnerIndex=944|IndexInSheet=-1|OwnerPartId=-1|Color=8388608|FontID=1|Text=2D|Name=Available Preview Images
|RECORD=1|LibReference=CAP|ComponentDescription=C0603X104K5RACAUTO|PartCount=2|DisplayModeCount=2|IndexInSheet=69|OwnerPartId=-1|Location.X=1070|Location.Y=790|Orientation=1|CurrentPartId=1|SourceLibraryName=Altium Content Vault|TargetFileName=*|AreaColor=11599871|Color=128|PartIDLocked=F|DesignItemId=CMP-2006-00003-1|AllPinCount=2
|RECORD=2|OwnerIndex=946|OwnerPartId=1|OwnerPartDisplayMode=1|FormalType=1|Electrical=4|PinConglomerate=35|PinLength=10|Location.X=1080|Location.Y=790|Name=1|Designator=1|PinPropagationDelay=0.000000E+000
|RECORD=2|OwnerIndex=946|OwnerPartId=1|OwnerPartDisplayMode=1|FormalType=1|Electrical=4|PinConglomerate=33|PinLength=10|Location.X=1080|Location.Y=800|Name=2|Designator=2|PinPropagationDelay=0.000000E+000
|RECORD=13|OwnerIndex=946|IsNotAccesible=T|IndexInSheet=2|OwnerPartId=1|OwnerPartDisplayMode=1|Location.X=1088|Location.Y=790|Corner.X=1072|Corner.Y=790|LineWidth=1|Color=16711680
|RECORD=13|OwnerIndex=946|IsNotAccesible=T|IndexInSheet=3|OwnerPartId=1|OwnerPartDisplayMode=1|Location.X=1080|Location.Y=794|Corner.X=1080|Corner.Y=800|LineWidth=1|Color=16711680
|RECORD=12|OwnerIndex=946|IsNotAccesible=T|IndexInSheet=4|OwnerPartId=1|OwnerPartDisplayMode=1|Location.X=1080|Location.Y=810|Radius=16|LineWidth=1|StartAngle=241.000|EndAngle=270.000|Color=16711680
|RECORD=12|OwnerIndex=946|IsNotAccesible=T|IndexInSheet=5|OwnerPartId=1|OwnerPartDisplayMode=1|Location.X=1080|Location.Y=810|Radius=16|LineWidth=1|StartAngle=270.000|EndAngle=299.000|Color=16711680
|RECORD=2|OwnerIndex=946|OwnerPartId=1|FormalType=1|Electrical=4|PinConglomerate=35|PinLength=10|Location.X=1080|Location.Y=790|Name=1|Designator=1|PinPropagationDelay=0.000000E+000
|RECORD=2|OwnerIndex=946|OwnerPartId=1|FormalType=1|Electrical=4|PinConglomerate=33|PinLength=10|Location.X=1080|Location.Y=800|Name=2|Designator=2|PinPropagationDelay=0.000000E+000
|RECORD=13|OwnerIndex=946|IsNotAccesible=T|IndexInSheet=8|OwnerPartId=1|Location.X=1072|Location.Y=797|Corner.X=1088|Corner.Y=797|LineWidth=1|Color=16711680
|RECORD=13|OwnerIndex=946|IsNotAccesible=T|IndexInSheet=9|OwnerPartId=1|Location.X=1088|Location.Y=793|Corner.X=1072|Corner.Y=793|LineWidth=1|Color=16711680
|RECORD=6|OwnerIndex=946|IsNotAccesible=T|IndexInSheet=10|OwnerPartId=1|LineWidth=1|Color=16711680|LocationCount=2|X1=1080|Y1=790|X2=1080|Y2=793
|RECORD=6|OwnerIndex=946|IsNotAccesible=T|IndexInSheet=11|OwnerPartId=1|LineWidth=1|Color=16711680|LocationCount=2|X1=1080|Y1=800|X2=1080|Y2=797
|RECORD=41|OwnerIndex=946|IndexInSheet=12|OwnerPartId=-1|Location.X=1071|Location.Y=812|Color=8388608|FontID=1|IsHidden=T|Text=Kemet|Name=Manufacturer
|RECORD=41|OwnerIndex=946|IndexInSheet=13|OwnerPartId=-1|Location.X=1071|Location.Y=812|Color=8388608|FontID=1|IsHidden=T|Text=C0603X104K5RACAUTO|Name=Part Number
|RECORD=34|OwnerIndex=946|IndexInSheet=-1|OwnerPartId=-1|Location.X=1089|Location.Y=791|Color=8388608|FontID=5|Text=C15|Name=Designator|ReadOnlyState=1
|RECORD=41|OwnerIndex=946|IndexInSheet=-1|OwnerPartId=-1|Location.X=1089|Location.Y=781|Color=8388608|FontID=5|Text=0.1uF|Name=Comment
|RECORD=44|OwnerIndex=946
|RECORD=45|OwnerIndex=967|IndexInSheet=-1|Description=Chip Capacitor, 2-Leads, Body 1.60x0.80mm, IPC Low Density|UseComponentLibrary=T|ModelName=CAPC1608X87X45ML20T05|ModelType=PCBLIB|DatafileCount=1|ModelDatafileEntity0=CAPC1608X87X45ML20T05|ModelDatafileKind0=PCBLib|IsCurrent=T|DatalinksLocked=T|DatabaseDatalinksLocked=T
|RECORD=46|OwnerIndex=968
|RECORD=48|OwnerIndex=968
|RECORD=41|OwnerIndex=970|IndexInSheet=-1|OwnerPartId=-1|Color=8388608|FontID=1|Text=2D|Name=Available Preview Images
|RECORD=45|OwnerIndex=967|IndexInSheet=-1|Description=Chip Capacitor, 2-Leads, Body 1.60x0.80mm, IPC High Density|UseComponentLibrary=T|ModelName=CAPC1608X87X45LL20T05|ModelType=PCBLIB|DatafileCount=1|ModelDatafileEntity0=CAPC1608X87X45LL20T05|ModelDatafileKind0=PCBLib|DatalinksLocked=T|DatabaseDatalinksLocked=T
|RECORD=46|OwnerIndex=972
|RECORD=48|OwnerIndex=972
|RECORD=41|OwnerIndex=974|IndexInSheet=-1|OwnerPartId=-1|Color=8388608|FontID=1|Text=2D|Name=Available Preview Images
|RECORD=45|OwnerIndex=967|IndexInSheet=-1|Description=Chip Capacitor, 2-Leads, Body 1.60x0.80mm, IPC Medium Density|UseComponentLibrary=T|ModelName=CAPC1608X87X45NL20T05|ModelType=PCBLIB|DatafileCount=1|ModelDatafileEntity0=CAPC1608X87X45NL20T05|ModelDatafileKind0=PCBLib|DatalinksLocked=T|DatabaseDatalinksLocked=T
|RECORD=46|OwnerIndex=976
|RECORD=48|OwnerIndex=976
|RECORD=41|OwnerIndex=978|IndexInSheet=-1|OwnerPartId=-1|Color=8388608|FontID=1|Text=2D|Name=Available Preview Images
|RECORD=1|LibReference=CAP|ComponentDescription=C0603X104K5RACAUTO|PartCount=2|DisplayModeCount=2|IndexInSheet=70|OwnerPartId=-1|Location.X=1120|Location.Y=790|Orientation=1|CurrentPartId=1|SourceLibraryName=Altium Content Vault|TargetFileName=*|AreaColor=11599871|Color=128|PartIDLocked=F|DesignItemId=CMP-2006-00003-1|AllPinCount=2
|RECORD=2|OwnerIndex=980|OwnerPartId=1|OwnerPartDisplayMode=1|FormalType=1|Electrical=4|PinConglomerate=35|PinLength=10|Location.X=1130|Location.Y=790|Name=1|Designator=1|PinPropagationDelay=0.000000E+000
|RECORD=2|OwnerIndex=980|OwnerPartId=1|OwnerPartDisplayMode=1|FormalType=1|Electrical=4|PinConglomerate=33|PinLength=10|Location.X=1130|Location.Y=800|Name=2|Designator=2|PinPropagationDelay=0.000000E+000
|RECORD=13|OwnerIndex=980|IsNotAccesible=T|IndexInSheet=2|OwnerPartId=1|OwnerPartDisplayMode=1|Location.X=1138|Location.Y=790|Corner.X=1122|Corner.Y=790|LineWidth=1|Color=16711680
|RECORD=13|OwnerIndex=980|IsNotAccesible=T|IndexInSheet=3|OwnerPartId=1|OwnerPartDisplayMode=1|Location.X=1130|Location.Y=794|Corner.X=1130|Corner.Y=800|LineWidth=1|Color=16711680
|RECORD=12|OwnerIndex=980|IsNotAccesible=T|IndexInSheet=4|OwnerPartId=1|OwnerPartDisplayMode=1|Location.X=1130|Location.Y=810|Radius=16|LineWidth=1|StartAngle=241.000|EndAngle=270.000|Color=16711680
|RECORD=12|OwnerIndex=980|IsNotAccesible=T|IndexInSheet=5|OwnerPartId=1|OwnerPartDisplayMode=1|Location.X=1130|Location.Y=810|Radius=16|LineWidth=1|StartAngle=270.000|EndAngle=299.000|Color=16711680
|RECORD=2|OwnerIndex=980|OwnerPartId=1|FormalType=1|Electrical=4|PinConglomerate=35|PinLength=10|Location.X=1130|Location.Y=790|Name=1|Designator=1|PinPropagationDelay=0.000000E+000
|RECORD=2|OwnerIndex=980|OwnerPartId=1|FormalType=1|Electrical=4|PinConglomerate=33|PinLength=10|Location.X=1130|Location.Y=800|Name=2|Designator=2|PinPropagationDelay=0.000000E+000
|RECORD=13|OwnerIndex=980|IsNotAccesible=T|IndexInSheet=8|OwnerPartId=1|Location.X=1122|Location.Y=797|Corner.X=1138|Corner.Y=797|LineWidth=1|Color=16711680
|RECORD=13|OwnerIndex=980|IsNotAccesible=T|IndexInSheet=9|OwnerPartId=1|Location.X=1138|Location.Y=793|Corner.X=1122|Corner.Y=793|LineWidth=1|Color=16711680
|RECORD=6|OwnerIndex=980|IsNotAccesible=T|IndexInSheet=10|OwnerPartId=1|LineWidth=1|Color=16711680|LocationCount=2|X1=1130|Y1=790|X2=1130|Y2=793
|RECORD=6|OwnerIndex=980|IsNotAccesible=T|IndexInSheet=11|OwnerPartId=1|LineWidth=1|Color=16711680|LocationCount=2|X1=1130|Y1=800|X2=1130|Y2=797
|RECORD=41|OwnerIndex=980|IndexInSheet=12|OwnerPartId=-1|Location.X=1121|Location.Y=812|Color=8388608|FontID=1|IsHidden=T|Text=Kemet|Name=Manufacturer
|RECORD=41|OwnerIndex=980|IndexInSheet=13|OwnerPartId=-1|Location.X=1121|Location.Y=812|Color=8388608|FontID=1|IsHidden=T|Text=C0603X104K5RACAUTO|Name=Part Number
|RECORD=34|OwnerIndex=980|IndexInSheet=-1|OwnerPartId=-1|Location.X=1139|Location.Y=791|Color=8388608|FontID=5|Text=C16|Name=Designator|ReadOnlyState=1
|RECORD=41|OwnerIndex=980|IndexInSheet=-1|OwnerPartId=-1|Location.X=1139|Location.Y=781|Color=8388608|FontID=5|Text=0.1uF|Name=Comment
|RECORD=44|OwnerIndex=980
|RECORD=45|OwnerIndex=1001|IndexInSheet=-1|Description=Chip Capacitor, 2-Leads, Body 1.60x0.80mm, IPC Low Density|UseComponentLibrary=T|ModelName=CAPC1608X87X45ML20T05|ModelType=PCBLIB|DatafileCount=1|ModelDatafileEntity0=CAPC1608X87X45ML20T05|ModelDatafileKind0=PCBLib|IsCurrent=T|DatalinksLocked=T|DatabaseDatalinksLocked=T
|RECORD=46|OwnerIndex=1002
|RECORD=48|OwnerIndex=1002
|RECORD=41|OwnerIndex=1004|IndexInSheet=-1|OwnerPartId=-1|Color=8388608|FontID=1|Text=2D|Name=Available Preview Images
|RECORD=45|OwnerIndex=1001|IndexInSheet=-1|Description=Chip Capacitor, 2-Leads, Body 1.60x0.80mm, IPC High Density|UseComponentLibrary=T|ModelName=CAPC1608X87X45LL20T05|ModelType=PCBLIB|DatafileCount=1|ModelDatafileEntity0=CAPC1608X87X45LL20T05|ModelDatafileKind0=PCBLib|DatalinksLocked=T|DatabaseDatalinksLocked=T
|RECORD=46|OwnerIndex=1006
|RECORD=48|OwnerIndex=1006
|RECORD=41|OwnerIndex=1008|IndexInSheet=-1|OwnerPartId=-1|Color=8388608|FontID=1|Text=2D|Name=Available Preview Images
|RECORD=45|OwnerIndex=1001|IndexInSheet=-1|Description=Chip Capacitor, 2-Leads, Body 1.60x0.80mm, IPC Medium Density|UseComponentLibrary=T|ModelName=CAPC1608X87X45NL20T05|ModelType=PCBLIB|DatafileCount=1|ModelDatafileEntity0=CAPC1608X87X45NL20T05|ModelDatafileKind0=PCBLib|DatalinksLocked=T|DatabaseDatalinksLocked=T
|RECORD=46|OwnerIndex=1010
|RECORD=48|OwnerIndex=1010
|RECORD=41|OwnerIndex=1012|IndexInSheet=-1|OwnerPartId=-1|Color=8388608|FontID=1|Text=2D|Name=Available Preview Images
|RECORD=1|LibReference=CAP|ComponentDescription=C0603X104K5RACAUTO|PartCount=2|DisplayModeCount=2|IndexInSheet=71|OwnerPartId=-1|Location.X=1170|Location.Y=790|Orientation=1|CurrentPartId=1|SourceLibraryName=Altium Content Vault|TargetFileName=*|AreaColor=11599871|Color=128|PartIDLocked=F|DesignItemId=CMP-2006-00003-1|AllPinCount=2
|RECORD=2|OwnerIndex=1014|OwnerPartId=1|OwnerPartDisplayMode=1|FormalType=1|Electrical=4|PinConglomerate=35|PinLength=10|Location.X=1180|Location.Y=790|Name=1|Designator=1|PinPropagationDelay=0.000000E+000
|RECORD=2|OwnerIndex=1014|OwnerPartId=1|OwnerPartDisplayMode=1|FormalType=1|Electrical=4|PinConglomerate=33|PinLength=10|Location.X=1180|Location.Y=800|Name=2|Designator=2|PinPropagationDelay=0.000000E+000
|RECORD=13|OwnerIndex=1014|IsNotAccesible=T|IndexInSheet=2|OwnerPartId=1|OwnerPartDisplayMode=1|Location.X=1188|Location.Y=790|Corner.X=1172|Corner.Y=790|LineWidth=1|Color=16711680
|RECORD=13|OwnerIndex=1014|IsNotAccesible=T|IndexInSheet=3|OwnerPartId=1|OwnerPartDisplayMode=1|Location.X=1180|Location.Y=794|Corner.X=1180|Corner.Y=800|LineWidth=1|Color=16711680
|RECORD=12|OwnerIndex=1014|IsNotAccesible=T|IndexInSheet=4|OwnerPartId=1|OwnerPartDisplayMode=1|Location.X=1180|Location.Y=810|Radius=16|LineWidth=1|StartAngle=241.000|EndAngle=270.000|Color=16711680
|RECORD=12|OwnerIndex=1014|IsNotAccesible=T|IndexInSheet=5|OwnerPartId=1|OwnerPartDisplayMode=1|Location.X=1180|Location.Y=810|Radius=16|LineWidth=1|StartAngle=270.000|EndAngle=299.000|Color=16711680
|RECORD=2|OwnerIndex=1014|OwnerPartId=1|FormalType=1|Electrical=4|PinConglomerate=35|PinLength=10|Location.X=1180|Location.Y=790|Name=1|Designator=1|PinPropagationDelay=0.000000E+000
|RECORD=2|OwnerIndex=1014|OwnerPartId=1|FormalType=1|Electrical=4|PinConglomerate=33|PinLength=10|Location.X=1180|Location.Y=800|Name=2|Designator=2|PinPropagationDelay=0.000000E+000
|RECORD=13|OwnerIndex=1014|IsNotAccesible=T|IndexInSheet=8|OwnerPartId=1|Location.X=1172|Location.Y=797|Corner.X=1188|Corner.Y=797|LineWidth=1|Color=16711680
|RECORD=13|OwnerIndex=1014|IsNotAccesible=T|IndexInSheet=9|OwnerPartId=1|Location.X=1188|Location.Y=793|Corner.X=1172|Corner.Y=793|LineWidth=1|Color=16711680
|RECORD=6|OwnerIndex=1014|IsNotAccesible=T|IndexInSheet=10|OwnerPartId=1|LineWidth=1|Color=16711680|LocationCount=2|X1=1180|Y1=790|X2=1180|Y2=793
|RECORD=6|OwnerIndex=1014|IsNotAccesible=T|IndexInSheet=11|OwnerPartId=1|LineWidth=1|Color=16711680|LocationCount=2|X1=1180|Y1=800|X2=1180|Y2=797
|RECORD=41|OwnerIndex=1014|IndexInSheet=12|OwnerPartId=-1|Location.X=1171|Location.Y=812|Color=8388608|FontID=1|IsHidden=T|Text=Kemet|Name=Manufacturer
|RECORD=41|OwnerIndex=1014|IndexInSheet=13|OwnerPartId=-1|Location.X=1171|Location.Y=812|Color=8388608|FontID=1|IsHidden=T|Text=C0603X104K5RACAUTO|Name=Part Number
|RECORD=34|OwnerIndex=1014|IndexInSheet=-1|OwnerPartId=-1|Location.X=1189|Location.Y=791|Color=8388608|FontID=5|Text=C17|Name=Designator|ReadOnlyState=1
|RECORD=41|OwnerIndex=1014|IndexInSheet=-1|OwnerPartId=-1|Location.X=1189|Location.Y=781|Color=8388608|FontID=5|Text=0.1uF|Name=Comment
|RECORD=44|OwnerIndex=1014
|RECORD=45|OwnerIndex=1035|IndexInSheet=-1|Description=Chip Capacitor, 2-Leads, Body 1.60x0.80mm, IPC Low Density|UseComponentLibrary=T|ModelName=CAPC1608X87X45ML20T05|ModelType=PCBLIB|DatafileCount=1|ModelDatafileEntity0=CAPC1608X87X45ML20T05|ModelDatafileKind0=PCBLib|IsCurrent=T|DatalinksLocked=T|DatabaseDatalinksLocked=T
|RECORD=46|OwnerIndex=1036
|RECORD=48|OwnerIndex=1036
|RECORD=41|OwnerIndex=1038|IndexInSheet=-1|OwnerPartId=-1|Color=8388608|FontID=1|Text=2D|Name=Available Preview Images
|RECORD=45|OwnerIndex=1035|IndexInSheet=-1|Description=Chip Capacitor, 2-Leads, Body 1.60x0.80mm, IPC High Density|UseComponentLibrary=T|ModelName=CAPC1608X87X45LL20T05|ModelType=PCBLIB|DatafileCount=1|ModelDatafileEntity0=CAPC1608X87X45LL20T05|ModelDatafileKind0=PCBLib|DatalinksLocked=T|DatabaseDatalinksLocked=T
|RECORD=46|OwnerIndex=1040
|RECORD=48|OwnerIndex=1040
|RECORD=41|OwnerIndex=1042|IndexInSheet=-1|OwnerPartId=-1|Color=8388608|FontID=1|Text=2D|Name=Available Preview Images
|RECORD=45|OwnerIndex=1035|IndexInSheet=-1|Description=Chip Capacitor, 2-Leads, Body 1.60x0.80mm, IPC Medium Density|UseComponentLibrary=T|ModelName=CAPC1608X87X45NL20T05|ModelType=PCBLIB|DatafileCount=1|ModelDatafileEntity0=CAPC1608X87X45NL20T05|ModelDatafileKind0=PCBLib|DatalinksLocked=T|DatabaseDatalinksLocked=T
|RECORD=46|OwnerIndex=1044
|RECORD=48|OwnerIndex=1044
|RECORD=41|OwnerIndex=1046|IndexInSheet=-1|OwnerPartId=-1|Color=8388608|FontID=1|Text=2D|Name=Available Preview Images
|RECORD=1|LibReference=CAP|ComponentDescription=C0603X104K5RACAUTO|PartCount=2|DisplayModeCount=2|IndexInSheet=72|OwnerPartId=-1|Location.X=1220|Location.Y=790|Orientation=1|CurrentPartId=1|SourceLibraryName=Altium Content Vault|TargetFileName=*|AreaColor=11599871|Color=128|PartIDLocked=F|DesignItemId=CMP-2006-00003-1|AllPinCount=2
|RECORD=2|OwnerIndex=1048|OwnerPartId=1|OwnerPartDisplayMode=1|FormalType=1|Electrical=4|PinConglomerate=35|PinLength=10|Location.X=1230|Location.Y=790|Name=1|Designator=1|PinPropagationDelay=0.000000E+000
|RECORD=2|OwnerIndex=1048|OwnerPartId=1|OwnerPartDisplayMode=1|FormalType=1|Electrical=4|PinConglomerate=33|PinLength=10|Location.X=1230|Location.Y=800|Name=2|Designator=2|PinPropagationDelay=0.000000E+000
|RECORD=13|OwnerIndex=1048|IsNotAccesible=T|IndexInSheet=2|OwnerPartId=1|OwnerPartDisplayMode=1|Location.X=1238|Location.Y=790|Corner.X=1222|Corner.Y=790|LineWidth=1|Color=16711680
|RECORD=13|OwnerIndex=1048|IsNotAccesible=T|IndexInSheet=3|OwnerPartId=1|OwnerPartDisplayMode=1|Location.X=1230|Location.Y=794|Corner.X=1230|Corner.Y=800|LineWidth=1|Color=16711680
|RECORD=12|OwnerIndex=1048|IsNotAccesible=T|IndexInSheet=4|OwnerPartId=1|OwnerPartDisplayMode=1|Location.X=1230|Location.Y=810|Radius=16|LineWidth=1|StartAngle=241.000|EndAngle=270.000|Color=16711680
|RECORD=12|OwnerIndex=1048|IsNotAccesible=T|IndexInSheet=5|OwnerPartId=1|OwnerPartDisplayMode=1|Location.X=1230|Location.Y=810|Radius=16|LineWidth=1|StartAngle=270.000|EndAngle=299.000|Color=16711680
|RECORD=2|OwnerIndex=1048|OwnerPartId=1|FormalType=1|Electrical=4|PinConglomerate=35|PinLength=10|Location.X=1230|Location.Y=790|Name=1|Designator=1|PinPropagationDelay=0.000000E+000
|RECORD=2|OwnerIndex=1048|OwnerPartId=1|FormalType=1|Electrical=4|PinConglomerate=33|PinLength=10|Location.X=1230|Location.Y=800|Name=2|Designator=2|PinPropagationDelay=0.000000E+000
|RECORD=13|OwnerIndex=1048|IsNotAccesible=T|IndexInSheet=8|OwnerPartId=1|Location.X=1222|Location.Y=797|Corner.X=1238|Corner.Y=797|LineWidth=1|Color=16711680
|RECORD=13|OwnerIndex=1048|IsNotAccesible=T|IndexInSheet=9|OwnerPartId=1|Location.X=1238|Location.Y=793|Corner.X=1222|Corner.Y=793|LineWidth=1|Color=16711680
|RECORD=6|OwnerIndex=1048|IsNotAccesible=T|IndexInSheet=10|OwnerPartId=1|LineWidth=1|Color=16711680|LocationCount=2|X1=1230|Y1=790|X2=1230|Y2=793
|RECORD=6|OwnerIndex=1048|IsNotAccesible=T|IndexInSheet=11|OwnerPartId=1|LineWidth=1|Color=16711680|LocationCount=2|X1=1230|Y1=800|X2=1230|Y2=797
|RECORD=41|OwnerIndex=1048|IndexInSheet=12|OwnerPartId=-1|Location.X=1221|Location.Y=812|Color=8388608|FontID=1|IsHidden=T|Text=Kemet|Name=Manufacturer
|RECORD=41|OwnerIndex=1048|IndexInSheet=13|OwnerPartId=-1|Location.X=1221|Location.Y=812|Color=8388608|FontID=1|IsHidden=T|Text=C0603X104K5RACAUTO|Name=Part Number
|RECORD=34|OwnerIndex=1048|IndexInSheet=-1|OwnerPartId=-1|Location.X=1239|Location.Y=791|Color=8388608|FontID=5|Text=C18|Name=Designator|ReadOnlyState=1
|RECORD=41|OwnerIndex=1048|IndexInSheet=-1|OwnerPartId=-1|Location.X=1239|Location.Y=781|Color=8388608|FontID=5|Text=0.1uF|Name=Comment
|RECORD=44|OwnerIndex=1048
|RECORD=45|OwnerIndex=1069|IndexInSheet=-1|Description=Chip Capacitor, 2-Leads, Body 1.60x0.80mm, IPC Low Density|UseComponentLibrary=T|ModelName=CAPC1608X87X45ML20T05|ModelType=PCBLIB|DatafileCount=1|ModelDatafileEntity0=CAPC1608X87X45ML20T05|ModelDatafileKind0=PCBLib|IsCurrent=T|DatalinksLocked=T|DatabaseDatalinksLocked=T
|RECORD=46|OwnerIndex=1070
|RECORD=48|OwnerIndex=1070
|RECORD=41|OwnerIndex=1072|IndexInSheet=-1|OwnerPartId=-1|Color=8388608|FontID=1|Text=2D|Name=Available Preview Images
|RECORD=45|OwnerIndex=1069|IndexInSheet=-1|Description=Chip Capacitor, 2-Leads, Body 1.60x0.80mm, IPC High Density|UseComponentLibrary=T|ModelName=CAPC1608X87X45LL20T05|ModelType=PCBLIB|DatafileCount=1|ModelDatafileEntity0=CAPC1608X87X45LL20T05|ModelDatafileKind0=PCBLib|DatalinksLocked=T|DatabaseDatalinksLocked=T
|RECORD=46|OwnerIndex=1074
|RECORD=48|OwnerIndex=1074
|RECORD=41|OwnerIndex=1076|IndexInSheet=-1|OwnerPartId=-1|Color=8388608|FontID=1|Text=2D|Name=Available Preview Images
|RECORD=45|OwnerIndex=1069|IndexInSheet=-1|Description=Chip Capacitor, 2-Leads, Body 1.60x0.80mm, IPC Medium Density|UseComponentLibrary=T|ModelName=CAPC1608X87X45NL20T05|ModelType=PCBLIB|DatafileCount=1|ModelDatafileEntity0=CAPC1608X87X45NL20T05|ModelDatafileKind0=PCBLib|DatalinksLocked=T|DatabaseDatalinksLocked=T
|RECORD=46|OwnerIndex=1078
|RECORD=48|OwnerIndex=1078
|RECORD=41|OwnerIndex=1080|IndexInSheet=-1|OwnerPartId=-1|Color=8388608|FontID=1|Text=2D|Name=Available Preview Images
|RECORD=1|LibReference=CAP|ComponentDescription=C0603X104K5RACAUTO|PartCount=2|DisplayModeCount=2|IndexInSheet=73|OwnerPartId=-1|Location.X=570|Location.Y=780|Orientation=1|CurrentPartId=1|SourceLibraryName=Altium Content Vault|TargetFileName=*|AreaColor=11599871|Color=128|PartIDLocked=F|DesignItemId=CMP-2006-00003-1|AllPinCount=2
|RECORD=2|OwnerIndex=1082|OwnerPartId=1|OwnerPartDisplayMode=1|FormalType=1|Electrical=4|PinConglomerate=35|PinLength=10|Location.X=580|Location.Y=780|Name=1|Designator=1|PinPropagationDelay=0.000000E+000
|RECORD=2|OwnerIndex=1082|OwnerPartId=1|OwnerPartDisplayMode=1|FormalType=1|Electrical=4|PinConglomerate=33|PinLength=10|Location.X=580|Location.Y=790|Name=2|Designator=2|PinPropagationDelay=0.000000E+000
|RECORD=13|OwnerIndex=1082|IsNotAccesible=T|IndexInSheet=2|OwnerPartId=1|OwnerPartDisplayMode=1|Location.X=588|Location.Y=780|Corner.X=572|Corner.Y=780|LineWidth=1|Color=16711680
|RECORD=13|OwnerIndex=1082|IsNotAccesible=T|IndexInSheet=3|OwnerPartId=1|OwnerPartDisplayMode=1|Location.X=580|Location.Y=784|Corner.X=580|Corner.Y=790|LineWidth=1|Color=16711680
|RECORD=12|OwnerIndex=1082|IsNotAccesible=T|IndexInSheet=4|OwnerPartId=1|OwnerPartDisplayMode=1|Location.X=580|Location.Y=800|Radius=16|LineWidth=1|StartAngle=241.000|EndAngle=270.000|Color=16711680
|RECORD=12|OwnerIndex=1082|IsNotAccesible=T|IndexInSheet=5|OwnerPartId=1|OwnerPartDisplayMode=1|Location.X=580|Location.Y=800|Radius=16|LineWidth=1|StartAngle=270.000|EndAngle=299.000|Color=16711680
|RECORD=2|OwnerIndex=1082|OwnerPartId=1|FormalType=1|Electrical=4|PinConglomerate=35|PinLength=10|Location.X=580|Location.Y=780|Name=1|Designator=1|PinPropagationDelay=0.000000E+000
|RECORD=2|OwnerIndex=1082|OwnerPartId=1|FormalType=1|Electrical=4|PinConglomerate=33|PinLength=10|Location.X=580|Location.Y=790|Name=2|Designator=2|PinPropagationDelay=0.000000E+000
|RECORD=13|OwnerIndex=1082|IsNotAccesible=T|IndexInSheet=8|OwnerPartId=1|Location.X=572|Location.Y=787|Corner.X=588|Corner.Y=787|LineWidth=1|Color=16711680
|RECORD=13|OwnerIndex=1082|IsNotAccesible=T|IndexInSheet=9|OwnerPartId=1|Location.X=588|Location.Y=783|Corner.X=572|Corner.Y=783|LineWidth=1|Color=16711680
|RECORD=6|OwnerIndex=1082|IsNotAccesible=T|IndexInSheet=10|OwnerPartId=1|LineWidth=1|Color=16711680|LocationCount=2|X1=580|Y1=780|X2=580|Y2=783
|RECORD=6|OwnerIndex=1082|IsNotAccesible=T|IndexInSheet=11|OwnerPartId=1|LineWidth=1|Color=16711680|LocationCount=2|X1=580|Y1=790|X2=580|Y2=787
|RECORD=41|OwnerIndex=1082|IndexInSheet=12|OwnerPartId=-1|Location.X=571|Location.Y=802|Color=8388608|FontID=1|IsHidden=T|Text=Kemet|Name=Manufacturer
|RECORD=41|OwnerIndex=1082|IndexInSheet=13|OwnerPartId=-1|Location.X=571|Location.Y=802|Color=8388608|FontID=1|IsHidden=T|Text=C0603X104K5RACAUTO|Name=Part Number
|RECORD=34|OwnerIndex=1082|IndexInSheet=-1|OwnerPartId=-1|Location.X=589|Location.Y=781|Color=8388608|FontID=5|Text=C19|Name=Designator|ReadOnlyState=1
|RECORD=41|OwnerIndex=1082|IndexInSheet=-1|OwnerPartId=-1|Location.X=589|Location.Y=771|Color=8388608|FontID=5|Text=0.1uF|Name=Comment
|RECORD=44|OwnerIndex=1082
|RECORD=45|OwnerIndex=1103|IndexInSheet=-1|Description=Chip Capacitor, 2-Leads, Body 1.60x0.80mm, IPC Low Density|UseComponentLibrary=T|ModelName=CAPC1608X87X45ML20T05|ModelType=PCBLIB|DatafileCount=1|ModelDatafileEntity0=CAPC1608X87X45ML20T05|ModelDatafileKind0=PCBLib|IsCurrent=T|DatalinksLocked=T|DatabaseDatalinksLocked=T
|RECORD=46|OwnerIndex=1104
|RECORD=48|OwnerIndex=1104
|RECORD=41|OwnerIndex=1106|IndexInSheet=-1|OwnerPartId=-1|Color=8388608|FontID=1|Text=2D|Name=Available Preview Images
|RECORD=45|OwnerIndex=1103|IndexInSheet=-1|Description=Chip Capacitor, 2-Leads, Body 1.60x0.80mm, IPC High Density|UseComponentLibrary=T|ModelName=CAPC1608X87X45LL20T05|ModelType=PCBLIB|DatafileCount=1|ModelDatafileEntity0=CAPC1608X87X45LL20T05|ModelDatafileKind0=PCBLib|DatalinksLocked=T|DatabaseDatalinksLocked=T
|RECORD=46|OwnerIndex=1108
|RECORD=48|OwnerIndex=1108
|RECORD=41|OwnerIndex=1110|IndexInSheet=-1|OwnerPartId=-1|Color=8388608|FontID=1|Text=2D|Name=Available Preview Images
|RECORD=45|OwnerIndex=1103|IndexInSheet=-1|Description=Chip Capacitor, 2-Leads, Body 1.60x0.80mm, IPC Medium Density|UseComponentLibrary=T|ModelName=CAPC1608X87X45NL20T05|ModelType=PCBLIB|DatafileCount=1|ModelDatafileEntity0=CAPC1608X87X45NL20T05|ModelDatafileKind0=PCBLib|DatalinksLocked=T|DatabaseDatalinksLocked=T
|RECORD=46|OwnerIndex=1112
|RECORD=48|OwnerIndex=1112
|RECORD=41|OwnerIndex=1114|IndexInSheet=-1|OwnerPartId=-1|Color=8388608|FontID=1|Text=2D|Name=Available Preview Images
|RECORD=1|LibReference=CAP|ComponentDescription=C0603X104K5RACAUTO|PartCount=2|DisplayModeCount=2|IndexInSheet=74|OwnerPartId=-1|Location.X=580|Location.Y=340|Orientation=1|CurrentPartId=1|SourceLibraryName=Altium Content Vault|TargetFileName=*|AreaColor=11599871|Color=128|PartIDLocked=F|DesignItemId=CMP-2006-00003-1|AllPinCount=2
|RECORD=2|OwnerIndex=1116|OwnerPartId=1|OwnerPartDisplayMode=1|FormalType=1|Electrical=4|PinConglomerate=35|PinLength=10|Location.X=590|Location.Y=340|Name=1|Designator=1|PinPropagationDelay=0.000000E+000
|RECORD=2|OwnerIndex=1116|OwnerPartId=1|OwnerPartDisplayMode=1|FormalType=1|Electrical=4|PinConglomerate=33|PinLength=10|Location.X=590|Location.Y=350|Name=2|Designator=2|PinPropagationDelay=0.000000E+000
|RECORD=13|OwnerIndex=1116|IsNotAccesible=T|IndexInSheet=2|OwnerPartId=1|OwnerPartDisplayMode=1|Location.X=598|Location.Y=340|Corner.X=582|Corner.Y=340|LineWidth=1|Color=16711680
|RECORD=13|OwnerIndex=1116|IsNotAccesible=T|IndexInSheet=3|OwnerPartId=1|OwnerPartDisplayMode=1|Location.X=590|Location.Y=344|Corner.X=590|Corner.Y=350|LineWidth=1|Color=16711680
|RECORD=12|OwnerIndex=1116|IsNotAccesible=T|IndexInSheet=4|OwnerPartId=1|OwnerPartDisplayMode=1|Location.X=590|Location.Y=360|Radius=16|LineWidth=1|StartAngle=241.000|EndAngle=270.000|Color=16711680
|RECORD=12|OwnerIndex=1116|IsNotAccesible=T|IndexInSheet=5|OwnerPartId=1|OwnerPartDisplayMode=1|Location.X=590|Location.Y=360|Radius=16|LineWidth=1|StartAngle=270.000|EndAngle=299.000|Color=16711680
|RECORD=2|OwnerIndex=1116|OwnerPartId=1|FormalType=1|Electrical=4|PinConglomerate=35|PinLength=10|Location.X=590|Location.Y=340|Name=1|Designator=1|PinPropagationDelay=0.000000E+000
|RECORD=2|OwnerIndex=1116|OwnerPartId=1|FormalType=1|Electrical=4|PinConglomerate=33|PinLength=10|Location.X=590|Location.Y=350|Name=2|Designator=2|PinPropagationDelay=0.000000E+000
|RECORD=13|OwnerIndex=1116|IsNotAccesible=T|IndexInSheet=8|OwnerPartId=1|Location.X=582|Location.Y=347|Corner.X=598|Corner.Y=347|LineWidth=1|Color=16711680
|RECORD=13|OwnerIndex=1116|IsNotAccesible=T|IndexInSheet=9|OwnerPartId=1|Location.X=598|Location.Y=343|Corner.X=582|Corner.Y=343|LineWidth=1|Color=16711680
|RECORD=6|OwnerIndex=1116|IsNotAccesible=T|IndexInSheet=10|OwnerPartId=1|LineWidth=1|Color=16711680|LocationCount=2|X1=590|Y1=340|X2=590|Y2=343
|RECORD=6|OwnerIndex=1116|IsNotAccesible=T|IndexInSheet=11|OwnerPartId=1|LineWidth=1|Color=16711680|LocationCount=2|X1=590|Y1=350|X2=590|Y2=347
|RECORD=41|OwnerIndex=1116|IndexInSheet=12|OwnerPartId=-1|Location.X=581|Location.Y=362|Color=8388608|FontID=1|IsHidden=T|Text=Kemet|Name=Manufacturer
|RECORD=41|OwnerIndex=1116|IndexInSheet=13|OwnerPartId=-1|Location.X=581|Location.Y=362|Color=8388608|FontID=1|IsHidden=T|Text=C0603X104K5RACAUTO|Name=Part Number
|RECORD=34|OwnerIndex=1116|IndexInSheet=-1|OwnerPartId=-1|Location.X=599|Location.Y=341|Color=8388608|FontID=5|Text=C21|Name=Designator|ReadOnlyState=1
|RECORD=41|OwnerIndex=1116|IndexInSheet=-1|OwnerPartId=-1|Location.X=599|Location.Y=331|Color=8388608|FontID=5|Text=0.1uF|Name=Comment
|RECORD=44|OwnerIndex=1116
|RECORD=45|OwnerIndex=1137|IndexInSheet=-1|Description=Chip Capacitor, 2-Leads, Body 1.60x0.80mm, IPC Low Density|UseComponentLibrary=T|ModelName=CAPC1608X87X45ML20T05|ModelType=PCBLIB|DatafileCount=1|ModelDatafileEntity0=CAPC1608X87X45ML20T05|ModelDatafileKind0=PCBLib|IsCurrent=T|DatalinksLocked=T|DatabaseDatalinksLocked=T
|RECORD=46|OwnerIndex=1138
|RECORD=48|OwnerIndex=1138
|RECORD=41|OwnerIndex=1140|IndexInSheet=-1|OwnerPartId=-1|Color=8388608|FontID=1|Text=2D|Name=Available Preview Images
|RECORD=45|OwnerIndex=1137|IndexInSheet=-1|Description=Chip Capacitor, 2-Leads, Body 1.60x0.80mm, IPC High Density|UseComponentLibrary=T|ModelName=CAPC1608X87X45LL20T05|ModelType=PCBLIB|DatafileCount=1|ModelDatafileEntity0=CAPC1608X87X45LL20T05|ModelDatafileKind0=PCBLib|DatalinksLocked=T|DatabaseDatalinksLocked=T
|RECORD=46|OwnerIndex=1142
|RECORD=48|OwnerIndex=1142
|RECORD=41|OwnerIndex=1144|IndexInSheet=-1|OwnerPartId=-1|Color=8388608|FontID=1|Text=2D|Name=Available Preview Images
|RECORD=45|OwnerIndex=1137|IndexInSheet=-1|Description=Chip Capacitor, 2-Leads, Body 1.60x0.80mm, IPC Medium Density|UseComponentLibrary=T|ModelName=CAPC1608X87X45NL20T05|ModelType=PCBLIB|DatafileCount=1|ModelDatafileEntity0=CAPC1608X87X45NL20T05|ModelDatafileKind0=PCBLib|DatalinksLocked=T|DatabaseDatalinksLocked=T
|RECORD=46|OwnerIndex=1146
|RECORD=48|OwnerIndex=1146
|RECORD=41|OwnerIndex=1148|IndexInSheet=-1|OwnerPartId=-1|Color=8388608|FontID=1|Text=2D|Name=Available Preview Images
|RECORD=1|LibReference=CAP|ComponentDescription=C0603X104K5RACAUTO|PartCount=2|DisplayModeCount=2|IndexInSheet=75|OwnerPartId=-1|Location.X=1060|Location.Y=390|Orientation=1|CurrentPartId=1|SourceLibraryName=Altium Content Vault|TargetFileName=*|AreaColor=11599871|Color=128|PartIDLocked=F|DesignItemId=CMP-2006-00003-1|AllPinCount=2
|RECORD=2|OwnerIndex=1150|OwnerPartId=1|OwnerPartDisplayMode=1|FormalType=1|Electrical=4|PinConglomerate=35|PinLength=10|Location.X=1070|Location.Y=390|Name=1|Designator=1|PinPropagationDelay=0.000000E+000
|RECORD=2|OwnerIndex=1150|OwnerPartId=1|OwnerPartDisplayMode=1|FormalType=1|Electrical=4|PinConglomerate=33|PinLength=10|Location.X=1070|Location.Y=400|Name=2|Designator=2|PinPropagationDelay=0.000000E+000
|RECORD=13|OwnerIndex=1150|IsNotAccesible=T|IndexInSheet=2|OwnerPartId=1|OwnerPartDisplayMode=1|Location.X=1078|Location.Y=390|Corner.X=1062|Corner.Y=390|LineWidth=1|Color=16711680
|RECORD=13|OwnerIndex=1150|IsNotAccesible=T|IndexInSheet=3|OwnerPartId=1|OwnerPartDisplayMode=1|Location.X=1070|Location.Y=394|Corner.X=1070|Corner.Y=400|LineWidth=1|Color=16711680
|RECORD=12|OwnerIndex=1150|IsNotAccesible=T|IndexInSheet=4|OwnerPartId=1|OwnerPartDisplayMode=1|Location.X=1070|Location.Y=410|Radius=16|LineWidth=1|StartAngle=241.000|EndAngle=270.000|Color=16711680
|RECORD=12|OwnerIndex=1150|IsNotAccesible=T|IndexInSheet=5|OwnerPartId=1|OwnerPartDisplayMode=1|Location.X=1070|Location.Y=410|Radius=16|LineWidth=1|StartAngle=270.000|EndAngle=299.000|Color=16711680
|RECORD=2|OwnerIndex=1150|OwnerPartId=1|FormalType=1|Electrical=4|PinConglomerate=35|PinLength=10|Location.X=1070|Location.Y=390|Name=1|Designator=1|PinPropagationDelay=0.000000E+000
|RECORD=2|OwnerIndex=1150|OwnerPartId=1|FormalType=1|Electrical=4|PinConglomerate=33|PinLength=10|Location.X=1070|Location.Y=400|Name=2|Designator=2|PinPropagationDelay=0.000000E+000
|RECORD=13|OwnerIndex=1150|IsNotAccesible=T|IndexInSheet=8|OwnerPartId=1|Location.X=1062|Location.Y=397|Corner.X=1078|Corner.Y=397|LineWidth=1|Color=16711680
|RECORD=13|OwnerIndex=1150|IsNotAccesible=T|IndexInSheet=9|OwnerPartId=1|Location.X=1078|Location.Y=393|Corner.X=1062|Corner.Y=393|LineWidth=1|Color=16711680
|RECORD=6|OwnerIndex=1150|IsNotAccesible=T|IndexInSheet=10|OwnerPartId=1|LineWidth=1|Color=16711680|LocationCount=2|X1=1070|Y1=390|X2=1070|Y2=393
|RECORD=6|OwnerIndex=1150|IsNotAccesible=T|IndexInSheet=11|OwnerPartId=1|LineWidth=1|Color=16711680|LocationCount=2|X1=1070|Y1=400|X2=1070|Y2=397
|RECORD=41|OwnerIndex=1150|IndexInSheet=12|OwnerPartId=-1|Location.X=1061|Location.Y=412|Color=8388608|FontID=1|IsHidden=T|Text=Kemet|Name=Manufacturer
|RECORD=41|OwnerIndex=1150|IndexInSheet=13|OwnerPartId=-1|Location.X=1061|Location.Y=412|Color=8388608|FontID=1|IsHidden=T|Text=C0603X104K5RACAUTO|Name=Part Number
|RECORD=34|OwnerIndex=1150|IndexInSheet=-1|OwnerPartId=-1|Location.X=1079|Location.Y=391|Color=8388608|FontID=5|Text=C9|Name=Designator|ReadOnlyState=1
|RECORD=41|OwnerIndex=1150|IndexInSheet=-1|OwnerPartId=-1|Location.X=1080|Location.Y=380|Color=8388608|FontID=5|Text=0.1uF|Name=Comment
|RECORD=44|OwnerIndex=1150
|RECORD=45|OwnerIndex=1171|IndexInSheet=-1|Description=Chip Capacitor, 2-Leads, Body 1.60x0.80mm, IPC Low Density|UseComponentLibrary=T|ModelName=CAPC1608X87X45ML20T05|ModelType=PCBLIB|DatafileCount=1|ModelDatafileEntity0=CAPC1608X87X45ML20T05|ModelDatafileKind0=PCBLib|IsCurrent=T|DatalinksLocked=T|DatabaseDatalinksLocked=T
|RECORD=46|OwnerIndex=1172
|RECORD=48|OwnerIndex=1172
|RECORD=41|OwnerIndex=1174|IndexInSheet=-1|OwnerPartId=-1|Color=8388608|FontID=1|Text=2D|Name=Available Preview Images
|RECORD=45|OwnerIndex=1171|IndexInSheet=-1|Description=Chip Capacitor, 2-Leads, Body 1.60x0.80mm, IPC High Density|UseComponentLibrary=T|ModelName=CAPC1608X87X45LL20T05|ModelType=PCBLIB|DatafileCount=1|ModelDatafileEntity0=CAPC1608X87X45LL20T05|ModelDatafileKind0=PCBLib|DatalinksLocked=T|DatabaseDatalinksLocked=T
|RECORD=46|OwnerIndex=1176
|RECORD=48|OwnerIndex=1176
|RECORD=41|OwnerIndex=1178|IndexInSheet=-1|OwnerPartId=-1|Color=8388608|FontID=1|Text=2D|Name=Available Preview Images
|RECORD=45|OwnerIndex=1171|IndexInSheet=-1|Description=Chip Capacitor, 2-Leads, Body 1.60x0.80mm, IPC Medium Density|UseComponentLibrary=T|ModelName=CAPC1608X87X45NL20T05|ModelType=PCBLIB|DatafileCount=1|ModelDatafileEntity0=CAPC1608X87X45NL20T05|ModelDatafileKind0=PCBLib|DatalinksLocked=T|DatabaseDatalinksLocked=T
|RECORD=46|OwnerIndex=1180
|RECORD=48|OwnerIndex=1180
|RECORD=41|OwnerIndex=1182|IndexInSheet=-1|OwnerPartId=-1|Color=8388608|FontID=1|Text=2D|Name=Available Preview Images
|RECORD=1|LibReference=CAP|ComponentDescription=C0603X104K5RACAUTO|PartCount=2|DisplayModeCount=2|IndexInSheet=76|OwnerPartId=-1|Location.X=1110|Location.Y=390|Orientation=1|CurrentPartId=1|SourceLibraryName=Altium Content Vault|TargetFileName=*|AreaColor=11599871|Color=128|PartIDLocked=F|DesignItemId=CMP-2006-00003-1|AllPinCount=2
|RECORD=2|OwnerIndex=1184|OwnerPartId=1|OwnerPartDisplayMode=1|FormalType=1|Electrical=4|PinConglomerate=35|PinLength=10|Location.X=1120|Location.Y=390|Name=1|Designator=1|PinPropagationDelay=0.000000E+000
|RECORD=2|OwnerIndex=1184|OwnerPartId=1|OwnerPartDisplayMode=1|FormalType=1|Electrical=4|PinConglomerate=33|PinLength=10|Location.X=1120|Location.Y=400|Name=2|Designator=2|PinPropagationDelay=0.000000E+000
|RECORD=13|OwnerIndex=1184|IsNotAccesible=T|IndexInSheet=2|OwnerPartId=1|OwnerPartDisplayMode=1|Location.X=1128|Location.Y=390|Corner.X=1112|Corner.Y=390|LineWidth=1|Color=16711680
|RECORD=13|OwnerIndex=1184|IsNotAccesible=T|IndexInSheet=3|OwnerPartId=1|OwnerPartDisplayMode=1|Location.X=1120|Location.Y=394|Corner.X=1120|Corner.Y=400|LineWidth=1|Color=16711680
|RECORD=12|OwnerIndex=1184|IsNotAccesible=T|IndexInSheet=4|OwnerPartId=1|OwnerPartDisplayMode=1|Location.X=1120|Location.Y=410|Radius=16|LineWidth=1|StartAngle=241.000|EndAngle=270.000|Color=16711680
|RECORD=12|OwnerIndex=1184|IsNotAccesible=T|IndexInSheet=5|OwnerPartId=1|OwnerPartDisplayMode=1|Location.X=1120|Location.Y=410|Radius=16|LineWidth=1|StartAngle=270.000|EndAngle=299.000|Color=16711680
|RECORD=2|OwnerIndex=1184|OwnerPartId=1|FormalType=1|Electrical=4|PinConglomerate=35|PinLength=10|Location.X=1120|Location.Y=390|Name=1|Designator=1|PinPropagationDelay=0.000000E+000
|RECORD=2|OwnerIndex=1184|OwnerPartId=1|FormalType=1|Electrical=4|PinConglomerate=33|PinLength=10|Location.X=1120|Location.Y=400|Name=2|Designator=2|PinPropagationDelay=0.000000E+000
|RECORD=13|OwnerIndex=1184|IsNotAccesible=T|IndexInSheet=8|OwnerPartId=1|Location.X=1112|Location.Y=397|Corner.X=1128|Corner.Y=397|LineWidth=1|Color=16711680
|RECORD=13|OwnerIndex=1184|IsNotAccesible=T|IndexInSheet=9|OwnerPartId=1|Location.X=1128|Location.Y=393|Corner.X=1112|Corner.Y=393|LineWidth=1|Color=16711680
|RECORD=6|OwnerIndex=1184|IsNotAccesible=T|IndexInSheet=10|OwnerPartId=1|LineWidth=1|Color=16711680|LocationCount=2|X1=1120|Y1=390|X2=1120|Y2=393
|RECORD=6|OwnerIndex=1184|IsNotAccesible=T|IndexInSheet=11|OwnerPartId=1|LineWidth=1|Color=16711680|LocationCount=2|X1=1120|Y1=400|X2=1120|Y2=397
|RECORD=41|OwnerIndex=1184|IndexInSheet=12|OwnerPartId=-1|Location.X=1111|Location.Y=412|Color=8388608|FontID=1|IsHidden=T|Text=Kemet|Name=Manufacturer
|RECORD=41|OwnerIndex=1184|IndexInSheet=13|OwnerPartId=-1|Location.X=1111|Location.Y=412|Color=8388608|FontID=1|IsHidden=T|Text=C0603X104K5RACAUTO|Name=Part Number
|RECORD=34|OwnerIndex=1184|IndexInSheet=-1|OwnerPartId=-1|Location.X=1129|Location.Y=391|Color=8388608|FontID=5|Text=C10|Name=Designator|ReadOnlyState=1
|RECORD=41|OwnerIndex=1184|IndexInSheet=-1|OwnerPartId=-1|Location.X=1129|Location.Y=381|Color=8388608|FontID=5|Text=0.1uF|Name=Comment
|RECORD=44|OwnerIndex=1184
|RECORD=45|OwnerIndex=1205|IndexInSheet=-1|Description=Chip Capacitor, 2-Leads, Body 1.60x0.80mm, IPC Low Density|UseComponentLibrary=T|ModelName=CAPC1608X87X45ML20T05|ModelType=PCBLIB|DatafileCount=1|ModelDatafileEntity0=CAPC1608X87X45ML20T05|ModelDatafileKind0=PCBLib|IsCurrent=T|DatalinksLocked=T|DatabaseDatalinksLocked=T
|RECORD=46|OwnerIndex=1206
|RECORD=48|OwnerIndex=1206
|RECORD=41|OwnerIndex=1208|IndexInSheet=-1|OwnerPartId=-1|Color=8388608|FontID=1|Text=2D|Name=Available Preview Images
|RECORD=45|OwnerIndex=1205|IndexInSheet=-1|Description=Chip Capacitor, 2-Leads, Body 1.60x0.80mm, IPC High Density|UseComponentLibrary=T|ModelName=CAPC1608X87X45LL20T05|ModelType=PCBLIB|DatafileCount=1|ModelDatafileEntity0=CAPC1608X87X45LL20T05|ModelDatafileKind0=PCBLib|DatalinksLocked=T|DatabaseDatalinksLocked=T
|RECORD=46|OwnerIndex=1210
|RECORD=48|OwnerIndex=1210
|RECORD=41|OwnerIndex=1212|IndexInSheet=-1|OwnerPartId=-1|Color=8388608|FontID=1|Text=2D|Name=Available Preview Images
|RECORD=45|OwnerIndex=1205|IndexInSheet=-1|Description=Chip Capacitor, 2-Leads, Body 1.60x0.80mm, IPC Medium Density|UseComponentLibrary=T|ModelName=CAPC1608X87X45NL20T05|ModelType=PCBLIB|DatafileCount=1|ModelDatafileEntity0=CAPC1608X87X45NL20T05|ModelDatafileKind0=PCBLib|DatalinksLocked=T|DatabaseDatalinksLocked=T
|RECORD=46|OwnerIndex=1214
|RECORD=48|OwnerIndex=1214
|RECORD=41|OwnerIndex=1216|IndexInSheet=-1|OwnerPartId=-1|Color=8388608|FontID=1|Text=2D|Name=Available Preview Images
|RECORD=1|LibReference=CAP|ComponentDescription=C0603X104K5RACAUTO|PartCount=2|DisplayModeCount=2|IndexInSheet=77|OwnerPartId=-1|Location.X=1160|Location.Y=390|Orientation=1|CurrentPartId=1|SourceLibraryName=Altium Content Vault|TargetFileName=*|AreaColor=11599871|Color=128|PartIDLocked=F|DesignItemId=CMP-2006-00003-1|AllPinCount=2
|RECORD=2|OwnerIndex=1218|OwnerPartId=1|OwnerPartDisplayMode=1|FormalType=1|Electrical=4|PinConglomerate=35|PinLength=10|Location.X=1170|Location.Y=390|Name=1|Designator=1|PinPropagationDelay=0.000000E+000
|RECORD=2|OwnerIndex=1218|OwnerPartId=1|OwnerPartDisplayMode=1|FormalType=1|Electrical=4|PinConglomerate=33|PinLength=10|Location.X=1170|Location.Y=400|Name=2|Designator=2|PinPropagationDelay=0.000000E+000
|RECORD=13|OwnerIndex=1218|IsNotAccesible=T|IndexInSheet=2|OwnerPartId=1|OwnerPartDisplayMode=1|Location.X=1178|Location.Y=390|Corner.X=1162|Corner.Y=390|LineWidth=1|Color=16711680
|RECORD=13|OwnerIndex=1218|IsNotAccesible=T|IndexInSheet=3|OwnerPartId=1|OwnerPartDisplayMode=1|Location.X=1170|Location.Y=394|Corner.X=1170|Corner.Y=400|LineWidth=1|Color=16711680
|RECORD=12|OwnerIndex=1218|IsNotAccesible=T|IndexInSheet=4|OwnerPartId=1|OwnerPartDisplayMode=1|Location.X=1170|Location.Y=410|Radius=16|LineWidth=1|StartAngle=241.000|EndAngle=270.000|Color=16711680
|RECORD=12|OwnerIndex=1218|IsNotAccesible=T|IndexInSheet=5|OwnerPartId=1|OwnerPartDisplayMode=1|Location.X=1170|Location.Y=410|Radius=16|LineWidth=1|StartAngle=270.000|EndAngle=299.000|Color=16711680
|RECORD=2|OwnerIndex=1218|OwnerPartId=1|FormalType=1|Electrical=4|PinConglomerate=35|PinLength=10|Location.X=1170|Location.Y=390|Name=1|Designator=1|PinPropagationDelay=0.000000E+000
|RECORD=2|OwnerIndex=1218|OwnerPartId=1|FormalType=1|Electrical=4|PinConglomerate=33|PinLength=10|Location.X=1170|Location.Y=400|Name=2|Designator=2|PinPropagationDelay=0.000000E+000
|RECORD=13|OwnerIndex=1218|IsNotAccesible=T|IndexInSheet=8|OwnerPartId=1|Location.X=1162|Location.Y=397|Corner.X=1178|Corner.Y=397|LineWidth=1|Color=16711680
|RECORD=13|OwnerIndex=1218|IsNotAccesible=T|IndexInSheet=9|OwnerPartId=1|Location.X=1178|Location.Y=393|Corner.X=1162|Corner.Y=393|LineWidth=1|Color=16711680
|RECORD=6|OwnerIndex=1218|IsNotAccesible=T|IndexInSheet=10|OwnerPartId=1|LineWidth=1|Color=16711680|LocationCount=2|X1=1170|Y1=390|X2=1170|Y2=393
|RECORD=6|OwnerIndex=1218|IsNotAccesible=T|IndexInSheet=11|OwnerPartId=1|LineWidth=1|Color=16711680|LocationCount=2|X1=1170|Y1=400|X2=1170|Y2=397
|RECORD=41|OwnerIndex=1218|IndexInSheet=12|OwnerPartId=-1|Location.X=1161|Location.Y=412|Color=8388608|FontID=1|IsHidden=T|Text=Kemet|Name=Manufacturer
|RECORD=41|OwnerIndex=1218|IndexInSheet=13|OwnerPartId=-1|Location.X=1161|Location.Y=412|Color=8388608|FontID=1|IsHidden=T|Text=C0603X104K5RACAUTO|Name=Part Number
|RECORD=34|OwnerIndex=1218|IndexInSheet=-1|OwnerPartId=-1|Location.X=1179|Location.Y=391|Color=8388608|FontID=5|Text=C11|Name=Designator|ReadOnlyState=1
|RECORD=41|OwnerIndex=1218|IndexInSheet=-1|OwnerPartId=-1|Location.X=1179|Location.Y=381|Color=8388608|FontID=5|Text=0.1uF|Name=Comment
|RECORD=44|OwnerIndex=1218
|RECORD=45|OwnerIndex=1239|IndexInSheet=-1|Description=Chip Capacitor, 2-Leads, Body 1.60x0.80mm, IPC Low Density|UseComponentLibrary=T|ModelName=CAPC1608X87X45ML20T05|ModelType=PCBLIB|DatafileCount=1|ModelDatafileEntity0=CAPC1608X87X45ML20T05|ModelDatafileKind0=PCBLib|IsCurrent=T|DatalinksLocked=T|DatabaseDatalinksLocked=T
|RECORD=46|OwnerIndex=1240
|RECORD=48|OwnerIndex=1240
|RECORD=41|OwnerIndex=1242|IndexInSheet=-1|OwnerPartId=-1|Color=8388608|FontID=1|Text=2D|Name=Available Preview Images
|RECORD=45|OwnerIndex=1239|IndexInSheet=-1|Description=Chip Capacitor, 2-Leads, Body 1.60x0.80mm, IPC High Density|UseComponentLibrary=T|ModelName=CAPC1608X87X45LL20T05|ModelType=PCBLIB|DatafileCount=1|ModelDatafileEntity0=CAPC1608X87X45LL20T05|ModelDatafileKind0=PCBLib|DatalinksLocked=T|DatabaseDatalinksLocked=T
|RECORD=46|OwnerIndex=1244
|RECORD=48|OwnerIndex=1244
|RECORD=41|OwnerIndex=1246|IndexInSheet=-1|OwnerPartId=-1|Color=8388608|FontID=1|Text=2D|Name=Available Preview Images
|RECORD=45|OwnerIndex=1239|IndexInSheet=-1|Description=Chip Capacitor, 2-Leads, Body 1.60x0.80mm, IPC Medium Density|UseComponentLibrary=T|ModelName=CAPC1608X87X45NL20T05|ModelType=PCBLIB|DatafileCount=1|ModelDatafileEntity0=CAPC1608X87X45NL20T05|ModelDatafileKind0=PCBLib|DatalinksLocked=T|DatabaseDatalinksLocked=T
|RECORD=46|OwnerIndex=1248
|RECORD=48|OwnerIndex=1248
|RECORD=41|OwnerIndex=1250|IndexInSheet=-1|OwnerPartId=-1|Color=8388608|FontID=1|Text=2D|Name=Available Preview Images
|RECORD=1|LibReference=CAP|ComponentDescription=C0603X104K5RACAUTO|PartCount=2|DisplayModeCount=2|IndexInSheet=78|OwnerPartId=-1|Location.X=1210|Location.Y=390|Orientation=1|CurrentPartId=1|SourceLibraryName=Altium Content Vault|TargetFileName=*|AreaColor=11599871|Color=128|PartIDLocked=F|DesignItemId=CMP-2006-00003-1|AllPinCount=2
|RECORD=2|OwnerIndex=1252|OwnerPartId=1|OwnerPartDisplayMode=1|FormalType=1|Electrical=4|PinConglomerate=35|PinLength=10|Location.X=1220|Location.Y=390|Name=1|Designator=1|PinPropagationDelay=0.000000E+000
|RECORD=2|OwnerIndex=1252|OwnerPartId=1|OwnerPartDisplayMode=1|FormalType=1|Electrical=4|PinConglomerate=33|PinLength=10|Location.X=1220|Location.Y=400|Name=2|Designator=2|PinPropagationDelay=0.000000E+000
|RECORD=13|OwnerIndex=1252|IsNotAccesible=T|IndexInSheet=2|OwnerPartId=1|OwnerPartDisplayMode=1|Location.X=1228|Location.Y=390|Corner.X=1212|Corner.Y=390|LineWidth=1|Color=16711680
|RECORD=13|OwnerIndex=1252|IsNotAccesible=T|IndexInSheet=3|OwnerPartId=1|OwnerPartDisplayMode=1|Location.X=1220|Location.Y=394|Corner.X=1220|Corner.Y=400|LineWidth=1|Color=16711680
|RECORD=12|OwnerIndex=1252|IsNotAccesible=T|IndexInSheet=4|OwnerPartId=1|OwnerPartDisplayMode=1|Location.X=1220|Location.Y=410|Radius=16|LineWidth=1|StartAngle=241.000|EndAngle=270.000|Color=16711680
|RECORD=12|OwnerIndex=1252|IsNotAccesible=T|IndexInSheet=5|OwnerPartId=1|OwnerPartDisplayMode=1|Location.X=1220|Location.Y=410|Radius=16|LineWidth=1|StartAngle=270.000|EndAngle=299.000|Color=16711680
|RECORD=2|OwnerIndex=1252|OwnerPartId=1|FormalType=1|Electrical=4|PinConglomerate=35|PinLength=10|Location.X=1220|Location.Y=390|Name=1|Designator=1|PinPropagationDelay=0.000000E+000
|RECORD=2|OwnerIndex=1252|OwnerPartId=1|FormalType=1|Electrical=4|PinConglomerate=33|PinLength=10|Location.X=1220|Location.Y=400|Name=2|Designator=2|PinPropagationDelay=0.000000E+000
|RECORD=13|OwnerIndex=1252|IsNotAccesible=T|IndexInSheet=8|OwnerPartId=1|Location.X=1212|Location.Y=397|Corner.X=1228|Corner.Y=397|LineWidth=1|Color=16711680
|RECORD=13|OwnerIndex=1252|IsNotAccesible=T|IndexInSheet=9|OwnerPartId=1|Location.X=1228|Location.Y=393|Corner.X=1212|Corner.Y=393|LineWidth=1|Color=16711680
|RECORD=6|OwnerIndex=1252|IsNotAccesible=T|IndexInSheet=10|OwnerPartId=1|LineWidth=1|Color=16711680|LocationCount=2|X1=1220|Y1=390|X2=1220|Y2=393
|RECORD=6|OwnerIndex=1252|IsNotAccesible=T|IndexInSheet=11|OwnerPartId=1|LineWidth=1|Color=16711680|LocationCount=2|X1=1220|Y1=400|X2=1220|Y2=397
|RECORD=41|OwnerIndex=1252|IndexInSheet=12|OwnerPartId=-1|Location.X=1211|Location.Y=412|Color=8388608|FontID=1|IsHidden=T|Text=Kemet|Name=Manufacturer
|RECORD=41|OwnerIndex=1252|IndexInSheet=13|OwnerPartId=-1|Location.X=1211|Location.Y=412|Color=8388608|FontID=1|IsHidden=T|Text=C0603X104K5RACAUTO|Name=Part Number
|RECORD=34|OwnerIndex=1252|IndexInSheet=-1|OwnerPartId=-1|Location.X=1229|Location.Y=391|Color=8388608|FontID=5|Text=C12|Name=Designator|ReadOnlyState=1
|RECORD=41|OwnerIndex=1252|IndexInSheet=-1|OwnerPartId=-1|Location.X=1229|Location.Y=381|Color=8388608|FontID=5|Text=0.1uF|Name=Comment
|RECORD=44|OwnerIndex=1252
|RECORD=45|OwnerIndex=1273|IndexInSheet=-1|Description=Chip Capacitor, 2-Leads, Body 1.60x0.80mm, IPC Low Density|UseComponentLibrary=T|ModelName=CAPC1608X87X45ML20T05|ModelType=PCBLIB|DatafileCount=1|ModelDatafileEntity0=CAPC1608X87X45ML20T05|ModelDatafileKind0=PCBLib|IsCurrent=T|DatalinksLocked=T|DatabaseDatalinksLocked=T
|RECORD=46|OwnerIndex=1274
|RECORD=48|OwnerIndex=1274
|RECORD=41|OwnerIndex=1276|IndexInSheet=-1|OwnerPartId=-1|Color=8388608|FontID=1|Text=2D|Name=Available Preview Images
|RECORD=45|OwnerIndex=1273|IndexInSheet=-1|Description=Chip Capacitor, 2-Leads, Body 1.60x0.80mm, IPC High Density|UseComponentLibrary=T|ModelName=CAPC1608X87X45LL20T05|ModelType=PCBLIB|DatafileCount=1|ModelDatafileEntity0=CAPC1608X87X45LL20T05|ModelDatafileKind0=PCBLib|DatalinksLocked=T|DatabaseDatalinksLocked=T
|RECORD=46|OwnerIndex=1278
|RECORD=48|OwnerIndex=1278
|RECORD=41|OwnerIndex=1280|IndexInSheet=-1|OwnerPartId=-1|Color=8388608|FontID=1|Text=2D|Name=Available Preview Images
|RECORD=45|OwnerIndex=1273|IndexInSheet=-1|Description=Chip Capacitor, 2-Leads, Body 1.60x0.80mm, IPC Medium Density|UseComponentLibrary=T|ModelName=CAPC1608X87X45NL20T05|ModelType=PCBLIB|DatafileCount=1|ModelDatafileEntity0=CAPC1608X87X45NL20T05|ModelDatafileKind0=PCBLib|DatalinksLocked=T|DatabaseDatalinksLocked=T
|RECORD=46|OwnerIndex=1282
|RECORD=48|OwnerIndex=1282
|RECORD=41|OwnerIndex=1284|IndexInSheet=-1|OwnerPartId=-1|Color=8388608|FontID=1|Text=2D|Name=Available Preview Images
|RECORD=1|LibReference=CAP|ComponentDescription=GCM188R71H333KA55D|PartCount=2|DisplayModeCount=2|IndexInSheet=79|OwnerPartId=-1|Location.X=710|Location.Y=310|Orientation=1|CurrentPartId=1|SourceLibraryName=Altium Content Vault|TargetFileName=*|AreaColor=11599871|Color=128|PartIDLocked=F|DesignItemId=CMP-2006-02385-1|AllPinCount=2
|RECORD=2|OwnerIndex=1286|OwnerPartId=1|OwnerPartDisplayMode=1|FormalType=1|Electrical=4|PinConglomerate=35|PinLength=10|Location.X=720|Location.Y=310|Name=1|Designator=1|PinPropagationDelay=0.000000E+000
|RECORD=2|OwnerIndex=1286|OwnerPartId=1|OwnerPartDisplayMode=1|FormalType=1|Electrical=4|PinConglomerate=33|PinLength=10|Location.X=720|Location.Y=320|Name=2|Designator=2|PinPropagationDelay=0.000000E+000
|RECORD=13|OwnerIndex=1286|IsNotAccesible=T|IndexInSheet=2|OwnerPartId=1|OwnerPartDisplayMode=1|Location.X=728|Location.Y=310|Corner.X=712|Corner.Y=310|LineWidth=1|Color=16711680
|RECORD=13|OwnerIndex=1286|IsNotAccesible=T|IndexInSheet=3|OwnerPartId=1|OwnerPartDisplayMode=1|Location.X=720|Location.Y=314|Corner.X=720|Corner.Y=320|LineWidth=1|Color=16711680
|RECORD=12|OwnerIndex=1286|IsNotAccesible=T|IndexInSheet=4|OwnerPartId=1|OwnerPartDisplayMode=1|Location.X=720|Location.Y=330|Radius=16|LineWidth=1|StartAngle=241.000|EndAngle=270.000|Color=16711680
|RECORD=12|OwnerIndex=1286|IsNotAccesible=T|IndexInSheet=5|OwnerPartId=1|OwnerPartDisplayMode=1|Location.X=720|Location.Y=330|Radius=16|LineWidth=1|StartAngle=270.000|EndAngle=299.000|Color=16711680
|RECORD=2|OwnerIndex=1286|OwnerPartId=1|FormalType=1|Electrical=4|PinConglomerate=35|PinLength=10|Location.X=720|Location.Y=310|Name=1|Designator=1|PinPropagationDelay=0.000000E+000
|RECORD=2|OwnerIndex=1286|OwnerPartId=1|FormalType=1|Electrical=4|PinConglomerate=33|PinLength=10|Location.X=720|Location.Y=320|Name=2|Designator=2|PinPropagationDelay=0.000000E+000
|RECORD=13|OwnerIndex=1286|IsNotAccesible=T|IndexInSheet=8|OwnerPartId=1|Location.X=712|Location.Y=317|Corner.X=728|Corner.Y=317|LineWidth=1|Color=16711680
|RECORD=13|OwnerIndex=1286|IsNotAccesible=T|IndexInSheet=9|OwnerPartId=1|Location.X=728|Location.Y=313|Corner.X=712|Corner.Y=313|LineWidth=1|Color=16711680
|RECORD=6|OwnerIndex=1286|IsNotAccesible=T|IndexInSheet=10|OwnerPartId=1|LineWidth=1|Color=16711680|LocationCount=2|X1=720|Y1=310|X2=720|Y2=313
|RECORD=6|OwnerIndex=1286|IsNotAccesible=T|IndexInSheet=11|OwnerPartId=1|LineWidth=1|Color=16711680|LocationCount=2|X1=720|Y1=320|X2=720|Y2=317
|RECORD=41|OwnerIndex=1286|IndexInSheet=12|OwnerPartId=-1|Location.X=711|Location.Y=332|Color=8388608|FontID=1|IsHidden=T|Text=Murata|Name=Manufacturer
|RECORD=41|OwnerIndex=1286|IndexInSheet=13|OwnerPartId=-1|Location.X=711|Location.Y=332|Color=8388608|FontID=1|IsHidden=T|Text=GCM188R71H333KA55D|Name=Part Number
|RECORD=34|OwnerIndex=1286|IndexInSheet=-1|OwnerPartId=-1|Location.X=729|Location.Y=311|Color=8388608|FontID=1|Text=C22|Name=Designator|ReadOnlyState=1
|RECORD=41|OwnerIndex=1286|IndexInSheet=-1|OwnerPartId=-1|Location.X=729|Location.Y=301|Color=8388608|FontID=1|Text=0.033uF|Name=Comment
|RECORD=44|OwnerIndex=1286
|RECORD=45|OwnerIndex=1307|IndexInSheet=-1|Description=Chip Capacitor, 2-Leads, Body 1.60x0.80mm, IPC Medium Density|UseComponentLibrary=T|ModelName=CAPC1608X90X35NL10T15|ModelType=PCBLIB|DatafileCount=1|ModelDatafileEntity0=CAPC1608X90X35NL10T15|ModelDatafileKind0=PCBLib|IsCurrent=T|DatalinksLocked=T|DatabaseDatalinksLocked=T
|RECORD=46|OwnerIndex=1308
|RECORD=48|OwnerIndex=1308
|RECORD=41|OwnerIndex=1310|IndexInSheet=-1|OwnerPartId=-1|Color=8388608|FontID=1|Text=2D|Name=Available Preview Images
|RECORD=45|OwnerIndex=1307|IndexInSheet=-1|Description=Chip Capacitor, 2-Leads, Body 1.60x0.80mm, IPC Low Density|UseComponentLibrary=T|ModelName=CAPC1608X90X35ML10T15|ModelType=PCBLIB|DatafileCount=1|ModelDatafileEntity0=CAPC1608X90X35ML10T15|ModelDatafileKind0=PCBLib|DatalinksLocked=T|DatabaseDatalinksLocked=T
|RECORD=46|OwnerIndex=1312
|RECORD=48|OwnerIndex=1312
|RECORD=41|OwnerIndex=1314|IndexInSheet=-1|OwnerPartId=-1|Color=8388608|FontID=1|Text=2D|Name=Available Preview Images
|RECORD=45|OwnerIndex=1307|IndexInSheet=-1|Description=Chip Capacitor, 2-Leads, Body 1.60x0.80mm, IPC High Density|UseComponentLibrary=T|ModelName=CAPC1608X90X35LL10T15|ModelType=PCBLIB|DatafileCount=1|ModelDatafileEntity0=CAPC1608X90X35LL10T15|ModelDatafileKind0=PCBLib|DatalinksLocked=T|DatabaseDatalinksLocked=T
|RECORD=46|OwnerIndex=1316
|RECORD=48|OwnerIndex=1316
|RECORD=41|OwnerIndex=1318|IndexInSheet=-1|OwnerPartId=-1|Color=8388608|FontID=1|Text=2D|Name=Available Preview Images
|RECORD=1|LibReference=CAP|ComponentDescription=GCM188R71H333KA55D|PartCount=2|DisplayModeCount=2|IndexInSheet=80|OwnerPartId=-1|Location.X=730|Location.Y=750|Orientation=1|CurrentPartId=1|SourceLibraryName=Altium Content Vault|TargetFileName=*|AreaColor=11599871|Color=128|PartIDLocked=F|DesignItemId=CMP-2006-02385-1|AllPinCount=2
|RECORD=2|OwnerIndex=1320|OwnerPartId=1|OwnerPartDisplayMode=1|FormalType=1|Electrical=4|PinConglomerate=35|PinLength=10|Location.X=740|Location.Y=750|Name=1|Designator=1|PinPropagationDelay=0.000000E+000
|RECORD=2|OwnerIndex=1320|OwnerPartId=1|OwnerPartDisplayMode=1|FormalType=1|Electrical=4|PinConglomerate=33|PinLength=10|Location.X=740|Location.Y=760|Name=2|Designator=2|PinPropagationDelay=0.000000E+000
|RECORD=13|OwnerIndex=1320|IsNotAccesible=T|IndexInSheet=2|OwnerPartId=1|OwnerPartDisplayMode=1|Location.X=748|Location.Y=750|Corner.X=732|Corner.Y=750|LineWidth=1|Color=16711680
|RECORD=13|OwnerIndex=1320|IsNotAccesible=T|IndexInSheet=3|OwnerPartId=1|OwnerPartDisplayMode=1|Location.X=740|Location.Y=754|Corner.X=740|Corner.Y=760|LineWidth=1|Color=16711680
|RECORD=12|OwnerIndex=1320|IsNotAccesible=T|IndexInSheet=4|OwnerPartId=1|OwnerPartDisplayMode=1|Location.X=740|Location.Y=770|Radius=16|LineWidth=1|StartAngle=241.000|EndAngle=270.000|Color=16711680
|RECORD=12|OwnerIndex=1320|IsNotAccesible=T|IndexInSheet=5|OwnerPartId=1|OwnerPartDisplayMode=1|Location.X=740|Location.Y=770|Radius=16|LineWidth=1|StartAngle=270.000|EndAngle=299.000|Color=16711680
|RECORD=2|OwnerIndex=1320|OwnerPartId=1|FormalType=1|Electrical=4|PinConglomerate=35|PinLength=10|Location.X=740|Location.Y=750|Name=1|Designator=1|PinPropagationDelay=0.000000E+000
|RECORD=2|OwnerIndex=1320|OwnerPartId=1|FormalType=1|Electrical=4|PinConglomerate=33|PinLength=10|Location.X=740|Location.Y=760|Name=2|Designator=2|PinPropagationDelay=0.000000E+000
|RECORD=13|OwnerIndex=1320|IsNotAccesible=T|IndexInSheet=8|OwnerPartId=1|Location.X=732|Location.Y=757|Corner.X=748|Corner.Y=757|LineWidth=1|Color=16711680
|RECORD=13|OwnerIndex=1320|IsNotAccesible=T|IndexInSheet=9|OwnerPartId=1|Location.X=748|Location.Y=753|Corner.X=732|Corner.Y=753|LineWidth=1|Color=16711680
|RECORD=6|OwnerIndex=1320|IsNotAccesible=T|IndexInSheet=10|OwnerPartId=1|LineWidth=1|Color=16711680|LocationCount=2|X1=740|Y1=750|X2=740|Y2=753
|RECORD=6|OwnerIndex=1320|IsNotAccesible=T|IndexInSheet=11|OwnerPartId=1|LineWidth=1|Color=16711680|LocationCount=2|X1=740|Y1=760|X2=740|Y2=757
|RECORD=41|OwnerIndex=1320|IndexInSheet=12|OwnerPartId=-1|Location.X=731|Location.Y=772|Color=8388608|FontID=1|IsHidden=T|Text=Murata|Name=Manufacturer
|RECORD=41|OwnerIndex=1320|IndexInSheet=13|OwnerPartId=-1|Location.X=731|Location.Y=772|Color=8388608|FontID=1|IsHidden=T|Text=GCM188R71H333KA55D|Name=Part Number
|RECORD=34|OwnerIndex=1320|IndexInSheet=-1|OwnerPartId=-1|Location.X=749|Location.Y=751|Color=8388608|FontID=1|Text=C20|Name=Designator|ReadOnlyState=1
|RECORD=41|OwnerIndex=1320|IndexInSheet=-1|OwnerPartId=-1|Location.X=749|Location.Y=741|Color=8388608|FontID=1|Text=0.033uF|Name=Comment
|RECORD=44|OwnerIndex=1320
|RECORD=45|OwnerIndex=1341|IndexInSheet=-1|Description=Chip Capacitor, 2-Leads, Body 1.60x0.80mm, IPC Medium Density|UseComponentLibrary=T|ModelName=CAPC1608X90X35NL10T15|ModelType=PCBLIB|DatafileCount=1|ModelDatafileEntity0=CAPC1608X90X35NL10T15|ModelDatafileKind0=PCBLib|IsCurrent=T|DatalinksLocked=T|DatabaseDatalinksLocked=T
|RECORD=46|OwnerIndex=1342
|RECORD=48|OwnerIndex=1342
|RECORD=41|OwnerIndex=1344|IndexInSheet=-1|OwnerPartId=-1|Color=8388608|FontID=1|Text=2D|Name=Available Preview Images
|RECORD=45|OwnerIndex=1341|IndexInSheet=-1|Description=Chip Capacitor, 2-Leads, Body 1.60x0.80mm, IPC Low Density|UseComponentLibrary=T|ModelName=CAPC1608X90X35ML10T15|ModelType=PCBLIB|DatafileCount=1|ModelDatafileEntity0=CAPC1608X90X35ML10T15|ModelDatafileKind0=PCBLib|DatalinksLocked=T|DatabaseDatalinksLocked=T
|RECORD=46|OwnerIndex=1346
|RECORD=48|OwnerIndex=1346
|RECORD=41|OwnerIndex=1348|IndexInSheet=-1|OwnerPartId=-1|Color=8388608|FontID=1|Text=2D|Name=Available Preview Images
|RECORD=45|OwnerIndex=1341|IndexInSheet=-1|Description=Chip Capacitor, 2-Leads, Body 1.60x0.80mm, IPC High Density|UseComponentLibrary=T|ModelName=CAPC1608X90X35LL10T15|ModelType=PCBLIB|DatafileCount=1|ModelDatafileEntity0=CAPC1608X90X35LL10T15|ModelDatafileKind0=PCBLib|DatalinksLocked=T|DatabaseDatalinksLocked=T
|RECORD=46|OwnerIndex=1350
|RECORD=48|OwnerIndex=1350
|RECORD=41|OwnerIndex=1352|IndexInSheet=-1|OwnerPartId=-1|Color=8388608|FontID=1|Text=2D|Name=Available Preview Images
|RECORD=41|IndexInSheet=81|OwnerPartId=-1|Color=8388608|FontID=1|IsHidden=T|Name=ConfigurationParameters|ReadOnlyState=1
|RECORD=41|IndexInSheet=82|OwnerPartId=-1|Color=8388608|FontID=1|IsHidden=T|Name=ConfiguratorName|ReadOnlyState=1
|RECORD=41|IndexInSheet=83|OwnerPartId=-1|Color=8388608|FontID=1|IsHidden=T|Name=VersionControl_RevNumber|ReadOnlyState=1
|RECORD=41|IndexInSheet=84|OwnerPartId=-1|Color=8388608|FontID=1|IsHidden=T|Name=IsUserConfigurable|ReadOnlyState=1
|RECORD=41|IndexInSheet=85|OwnerPartId=-1|Color=8388608|FontID=1|IsHidden=T|Name=VersionControl_ProjFolderRevNumber|ReadOnlyState=1
|RECORD=41|IndexInSheet=86|OwnerPartId=-1|Color=8388608|FontID=1|IsHidden=T|Name=SPICEModelCache|ReadOnlyState=1
|RECORD=27|IndexInSheet=87|OwnerPartId=-1|LineWidth=1|Color=8388608|LocationCount=4|X1=580|Y1=770|X2=580|Y2=730|X3=530|Y3=730|X4=530|Y4=910
|RECORD=27|IndexInSheet=88|OwnerPartId=-1|LineWidth=1|Color=8388608|LocationCount=5|X1=690|Y1=930|X2=690|Y2=960|X3=590|Y3=960|X4=530|Y4=960|X5=530|Y5=940
|RECORD=27|IndexInSheet=89|OwnerPartId=-1|LineWidth=1|Color=8388608|LocationCount=3|X1=690|Y1=780|X2=690|Y2=730|X3=580|Y3=730
|RECORD=27|IndexInSheet=90|OwnerPartId=-1|LineWidth=1|Color=8388608|LocationCount=3|X1=630|Y1=840|X2=580|Y2=840|X3=580|Y3=800
|RECORD=27|IndexInSheet=91|OwnerPartId=-1|LineWidth=1|Color=8388608|LocationCount=3|X1=590|Y1=900|X2=590|Y2=870|X3=630|Y3=870
|RECORD=27|IndexInSheet=92|OwnerPartId=-1|LineWidth=1|Color=8388608|LocationCount=3|X1=740|Y1=930|X2=740|Y2=960|X3=800|Y3=960
|RECORD=27|IndexInSheet=93|OwnerPartId=-1|LineWidth=1|Color=8388608|LocationCount=3|X1=800|Y1=840|X2=860|Y2=840|X3=870|Y3=840
|RECORD=27|IndexInSheet=94|OwnerPartId=-1|LineWidth=1|Color=8388608|LocationCount=4|X1=830|Y1=960|X2=850|Y2=960|X3=850|Y3=870|X4=800|Y4=870
|RECORD=27|IndexInSheet=95|OwnerPartId=-1|LineWidth=1|Color=8388608|LocationCount=7|X1=860|Y1=760|X2=860|Y2=730|X3=980|Y3=730|X4=1030|Y4=730|X5=1080|Y5=730|X6=1130|Y6=730|X7=1180|Y7=730
|RECORD=27|IndexInSheet=96|OwnerPartId=-1|LineWidth=1|Color=8388608|LocationCount=7|X1=920|Y1=840|X2=930|Y2=840|X3=980|Y3=840|X4=1030|Y4=840|X5=1080|Y5=840|X6=1130|Y6=840|X7=1180|Y7=840
|RECORD=27|IndexInSheet=97|OwnerPartId=-1|LineWidth=1|Color=8388608|LocationCount=4|X1=330|Y1=830|X2=330|Y2=820|X3=380|Y3=820|X4=380|Y4=810
|RECORD=27|IndexInSheet=98|OwnerPartId=-1|LineWidth=1|Color=8388608|LocationCount=3|X1=1180|Y1=730|X2=1230|Y2=730|X3=1230|Y3=780
|RECORD=27|IndexInSheet=99|OwnerPartId=-1|LineWidth=1|Color=8388608|LocationCount=3|X1=1180|Y1=840|X2=1230|Y2=840|X3=1230|Y3=810
|RECORD=27|IndexInSheet=100|OwnerPartId=-1|LineWidth=1|Color=8388608|LocationCount=5|X1=670|Y1=370|X2=670|Y2=280|X3=590|Y3=280|X4=530|Y4=280|X5=530|Y5=510
|RECORD=27|IndexInSheet=101|OwnerPartId=-1|LineWidth=1|Color=8388608|LocationCount=5|X1=670|Y1=520|X2=670|Y2=560|X3=590|Y3=560|X4=530|Y4=560|X5=530|Y5=540
|RECORD=27|IndexInSheet=102|OwnerPartId=-1|LineWidth=1|Color=8388608|LocationCount=3|X1=610|Y1=430|X2=590|Y2=430|X3=590|Y3=360
|RECORD=27|IndexInSheet=103|OwnerPartId=-1|LineWidth=1|Color=8388608|LocationCount=3|X1=610|Y1=460|X2=590|Y2=460|X3=590|Y3=490
|RECORD=27|IndexInSheet=104|OwnerPartId=-1|LineWidth=1|Color=8388608|LocationCount=3|X1=720|Y1=520|X2=720|Y2=560|X3=750|Y3=560
|RECORD=27|IndexInSheet=105|OwnerPartId=-1|LineWidth=1|Color=8388608|LocationCount=2|X1=810|Y1=430|X2=780|Y2=430
|RECORD=27|IndexInSheet=106|OwnerPartId=-1|LineWidth=1|Color=8388608|LocationCount=4|X1=780|Y1=560|X2=810|Y2=560|X3=810|Y3=460|X4=780|Y4=460
|RECORD=27|IndexInSheet=107|OwnerPartId=-1|LineWidth=1|Color=8388608|LocationCount=7|X1=1120|Y1=380|X2=1120|Y2=280|X3=1070|Y3=280|X4=1020|Y4=280|X5=970|Y5=280|X6=810|Y6=280|X7=810|Y7=310
|RECORD=27|IndexInSheet=108|OwnerPartId=-1|LineWidth=1|Color=8388608|LocationCount=3|X1=870|Y1=430|X2=810|Y2=430|X3=810|Y3=360
|RECORD=27|IndexInSheet=109|OwnerPartId=-1|LineWidth=1|Color=8388608|LocationCount=2|X1=810|Y1=460|X2=850|Y2=460
|RECORD=27|IndexInSheet=110|OwnerPartId=-1|LineWidth=1|Color=8388608|LocationCount=2|X1=920|Y1=430|X2=970|Y2=430
|RECORD=27|IndexInSheet=111|OwnerPartId=-1|LineWidth=1|Color=8388608|LocationCount=3|X1=930|Y1=460|X2=970|Y2=460|X3=970|Y3=430
|RECORD=27|IndexInSheet=112|OwnerPartId=-1|LineWidth=1|Color=8388608|LocationCount=5|X1=970|Y1=430|X2=1020|Y2=430|X3=1070|Y3=430|X4=1120|Y4=430|X5=1120|Y5=410
|RECORD=27|IndexInSheet=113|OwnerPartId=-1|LineWidth=1|Color=8388608|LocationCount=4|X1=1220|Y1=380|X2=1220|Y2=280|X3=1170|Y3=280|X4=1120|Y4=280
|RECORD=27|IndexInSheet=114|OwnerPartId=-1|LineWidth=1|Color=8388608|LocationCount=4|X1=1120|Y1=430|X2=1170|Y2=430|X3=1220|Y3=430|X4=1220|Y4=410
|RECORD=27|IndexInSheet=115|OwnerPartId=-1|LineWidth=1|Color=8388608|LocationCount=2|X1=590|Y1=950|X2=590|Y2=960
|RECORD=27|IndexInSheet=116|OwnerPartId=-1|LineWidth=1|Color=8388608|LocationCount=2|X1=740|Y1=730|X2=740|Y2=740
|RECORD=27|IndexInSheet=117|OwnerPartId=-1|LineWidth=1|Color=8388608|LocationCount=2|X1=740|Y1=770|X2=740|Y2=780
|RECORD=27|IndexInSheet=118|OwnerPartId=-1|LineWidth=1|Color=8388608|LocationCount=2|X1=860|Y1=840|X2=860|Y2=810
|RECORD=27|IndexInSheet=119|OwnerPartId=-1|LineWidth=1|Color=8388608|LocationCount=2|X1=930|Y1=870|X2=930|Y2=840
|RECORD=27|IndexInSheet=120|OwnerPartId=-1|LineWidth=1|Color=8388608|LocationCount=2|X1=930|Y1=950|X2=930|Y2=870
|RECORD=27|IndexInSheet=121|OwnerPartId=-1|LineWidth=1|Color=8388608|LocationCount=2|X1=980|Y1=780|X2=980|Y2=730
|RECORD=27|IndexInSheet=122|OwnerPartId=-1|LineWidth=1|Color=8388608|LocationCount=2|X1=980|Y1=810|X2=980|Y2=840
|RECORD=27|IndexInSheet=123|OwnerPartId=-1|LineWidth=1|Color=8388608|LocationCount=2|X1=1030|Y1=780|X2=1030|Y2=730
|RECORD=27|IndexInSheet=124|OwnerPartId=-1|LineWidth=1|Color=8388608|LocationCount=2|X1=1030|Y1=810|X2=1030|Y2=840
|RECORD=27|IndexInSheet=125|OwnerPartId=-1|LineWidth=1|Color=8388608|LocationCount=2|X1=1080|Y1=780|X2=1080|Y2=730
|RECORD=27|IndexInSheet=126|OwnerPartId=-1|LineWidth=1|Color=8388608|LocationCount=2|X1=1080|Y1=840|X2=1080|Y2=810
|RECORD=27|IndexInSheet=127|OwnerPartId=-1|LineWidth=1|Color=8388608|LocationCount=2|X1=330|Y1=860|X2=330|Y2=900
|RECORD=27|IndexInSheet=128|OwnerPartId=-1|LineWidth=1|Color=8388608|LocationCount=2|X1=1130|Y1=780|X2=1130|Y2=730
|RECORD=27|IndexInSheet=129|OwnerPartId=-1|LineWidth=1|Color=8388608|LocationCount=2|X1=1130|Y1=810|X2=1130|Y2=840
|RECORD=27|IndexInSheet=130|OwnerPartId=-1|LineWidth=1|Color=8388608|LocationCount=2|X1=380|Y1=830|X2=380|Y2=820
|RECORD=27|IndexInSheet=131|OwnerPartId=-1|LineWidth=1|Color=8388608|LocationCount=2|X1=380|Y1=900|X2=380|Y2=920
|RECORD=27|IndexInSheet=132|OwnerPartId=-1|LineWidth=1|Color=8388608|LocationCount=2|X1=1180|Y1=780|X2=1180|Y2=730
|RECORD=27|IndexInSheet=133|OwnerPartId=-1|LineWidth=1|Color=8388608|LocationCount=2|X1=1180|Y1=810|X2=1180|Y2=840
|RECORD=27|IndexInSheet=134|OwnerPartId=-1|LineWidth=1|Color=8388608|LocationCount=2|X1=590|Y1=330|X2=590|Y2=280
|RECORD=27|IndexInSheet=135|OwnerPartId=-1|LineWidth=1|Color=8388608|LocationCount=2|X1=590|Y1=540|X2=590|Y2=560
|RECORD=27|IndexInSheet=136|OwnerPartId=-1|LineWidth=1|Color=8388608|LocationCount=2|X1=720|Y1=280|X2=720|Y2=300
|RECORD=27|IndexInSheet=137|OwnerPartId=-1|LineWidth=1|Color=8388608|LocationCount=2|X1=720|Y1=330|X2=720|Y2=370
|RECORD=27|IndexInSheet=138|OwnerPartId=-1|LineWidth=1|Color=8388608|LocationCount=2|X1=970|Y1=380|X2=970|Y2=280
|RECORD=27|IndexInSheet=139|OwnerPartId=-1|LineWidth=1|Color=8388608|LocationCount=2|X1=970|Y1=410|X2=970|Y2=430
|RECORD=27|IndexInSheet=140|OwnerPartId=-1|LineWidth=1|Color=8388608|LocationCount=2|X1=970|Y1=460|X2=970|Y2=550
|RECORD=27|IndexInSheet=141|OwnerPartId=-1|LineWidth=1|Color=8388608|LocationCount=2|X1=1020|Y1=380|X2=1020|Y2=280
|RECORD=27|IndexInSheet=142|OwnerPartId=-1|LineWidth=1|Color=8388608|LocationCount=2|X1=1020|Y1=410|X2=1020|Y2=430
|RECORD=27|IndexInSheet=143|OwnerPartId=-1|LineWidth=1|Color=8388608|LocationCount=2|X1=1070|Y1=380|X2=1070|Y2=280
|RECORD=27|IndexInSheet=144|OwnerPartId=-1|LineWidth=1|Color=8388608|LocationCount=2|X1=1070|Y1=410|X2=1070|Y2=430
|RECORD=27|IndexInSheet=145|OwnerPartId=-1|LineWidth=1|Color=8388608|LocationCount=2|X1=1170|Y1=380|X2=1170|Y2=280
|RECORD=27|IndexInSheet=146|OwnerPartId=-1|LineWidth=1|Color=8388608|LocationCount=2|X1=1170|Y1=410|X2=1170|Y2=430
|RECORD=27|IndexInSheet=147|OwnerPartId=-1|LineWidth=1|Color=8388608|LocationCount=2|X1=1330|Y1=300|X2=1330|Y2=280
|RECORD=27|IndexInSheet=148|OwnerPartId=-1|LineWidth=1|Color=8388608|LocationCount=2|X1=1330|Y1=370|X2=1330|Y2=350
|RECORD=27|IndexInSheet=149|OwnerPartId=-1|LineWidth=1|Color=8388608|LocationCount=2|X1=1330|Y1=430|X2=1330|Y2=440
|RECORD=27|IndexInSheet=150|OwnerPartId=-1|LineWidth=1|Color=8388608|LocationCount=3|X1=140|Y1=930|X2=140|Y2=900|X3=160|Y3=900
|RECORD=27|IndexInSheet=151|OwnerPartId=-1|LineWidth=1|Color=8388608|LocationCount=2|X1=220|Y1=900|X2=230|Y2=900
|RECORD=27|IndexInSheet=152|OwnerPartId=-1|LineWidth=1|Color=8388608|LocationCount=4|X1=290|Y1=900|X2=330|Y2=900|X3=380|Y3=900|X4=380|Y4=860
|RECORD=29|IndexInSheet=-1|OwnerPartId=-1|Location.X=330|Location.Y=900|Color=128
|RECORD=29|IndexInSheet=-1|OwnerPartId=-1|Location.X=380|Location.Y=820|Color=128
|RECORD=29|IndexInSheet=-1|OwnerPartId=-1|Location.X=380|Location.Y=900|Color=128
|RECORD=29|IndexInSheet=-1|OwnerPartId=-1|Location.X=530|Location.Y=280|Color=128
|RECORD=29|IndexInSheet=-1|OwnerPartId=-1|Location.X=530|Location.Y=560|Color=128
|RECORD=29|IndexInSheet=-1|OwnerPartId=-1|Location.X=530|Location.Y=960|Color=128
|RECORD=29|IndexInSheet=-1|OwnerPartId=-1|Location.X=580|Location.Y=730|Color=128
|RECORD=29|IndexInSheet=-1|OwnerPartId=-1|Location.X=590|Location.Y=280|Color=128
|RECORD=29|IndexInSheet=-1|OwnerPartId=-1|Location.X=590|Location.Y=560|Color=128
|RECORD=29|IndexInSheet=-1|OwnerPartId=-1|Location.X=590|Location.Y=960|Color=128
|RECORD=29|IndexInSheet=-1|OwnerPartId=-1|Location.X=670|Location.Y=280|Color=128
|RECORD=29|IndexInSheet=-1|OwnerPartId=-1|Location.X=690|Location.Y=730|Color=128
|RECORD=29|IndexInSheet=-1|OwnerPartId=-1|Location.X=810|Location.Y=280|Color=128
|RECORD=29|IndexInSheet=-1|OwnerPartId=-1|Location.X=810|Location.Y=430|Color=128
|RECORD=29|IndexInSheet=-1|OwnerPartId=-1|Location.X=810|Location.Y=460|Color=128
|RECORD=29|IndexInSheet=-1|OwnerPartId=-1|Location.X=850|Location.Y=870|Color=128
|RECORD=29|IndexInSheet=-1|OwnerPartId=-1|Location.X=860|Location.Y=730|Color=128
|RECORD=29|IndexInSheet=-1|OwnerPartId=-1|Location.X=860|Location.Y=840|Color=128
|RECORD=29|IndexInSheet=-1|OwnerPartId=-1|Location.X=930|Location.Y=840|Color=128
|RECORD=29|IndexInSheet=-1|OwnerPartId=-1|Location.X=930|Location.Y=870|Color=128
|RECORD=29|IndexInSheet=-1|OwnerPartId=-1|Location.X=970|Location.Y=280|Color=128
|RECORD=29|IndexInSheet=-1|OwnerPartId=-1|Location.X=970|Location.Y=430|Color=128
|RECORD=29|IndexInSheet=-1|OwnerPartId=-1|Location.X=970|Location.Y=460|Color=128
|RECORD=29|IndexInSheet=-1|OwnerPartId=-1|Location.X=980|Location.Y=730|Color=128
|RECORD=29|IndexInSheet=-1|OwnerPartId=-1|Location.X=980|Location.Y=840|Color=128
|RECORD=29|IndexInSheet=-1|OwnerPartId=-1|Location.X=1020|Location.Y=280|Color=128
|RECORD=29|IndexInSheet=-1|OwnerPartId=-1|Location.X=1020|Location.Y=430|Color=128
|RECORD=29|IndexInSheet=-1|OwnerPartId=-1|Location.X=1030|Location.Y=730|Color=128
|RECORD=29|IndexInSheet=-1|OwnerPartId=-1|Location.X=1030|Location.Y=840|Color=128
|RECORD=29|IndexInSheet=-1|OwnerPartId=-1|Location.X=1070|Location.Y=280|Color=128
|RECORD=29|IndexInSheet=-1|OwnerPartId=-1|Location.X=1070|Location.Y=430|Color=128
|RECORD=29|IndexInSheet=-1|OwnerPartId=-1|Location.X=1080|Location.Y=730|Color=128
|RECORD=29|IndexInSheet=-1|OwnerPartId=-1|Location.X=1080|Location.Y=840|Color=128
|RECORD=29|IndexInSheet=-1|OwnerPartId=-1|Location.X=1120|Location.Y=280|Color=128
|RECORD=29|IndexInSheet=-1|OwnerPartId=-1|Location.X=1120|Location.Y=430|Color=128
|RECORD=29|IndexInSheet=-1|OwnerPartId=-1|Location.X=1130|Location.Y=730|Color=128
|RECORD=29|IndexInSheet=-1|OwnerPartId=-1|Location.X=1130|Location.Y=840|Color=128
|RECORD=29|IndexInSheet=-1|OwnerPartId=-1|Location.X=1170|Location.Y=280|Color=128
|RECORD=29|IndexInSheet=-1|OwnerPartId=-1|Location.X=1170|Location.Y=430|Color=128
|RECORD=29|IndexInSheet=-1|OwnerPartId=-1|Location.X=1180|Location.Y=730|Color=128
|RECORD=29|IndexInSheet=-1|OwnerPartId=-1|Location.X=1180|Location.Y=840|Color=128